G04 ================== begin FILE IDENTIFICATION RECORD ==================*
G04 Layout Name:  t6mg_pdb_a_v02_0109_1330.brd*
G04 Film Name:    vcc1*
G04 File Format:  Gerber RS274X*
G04 File Origin:  Cadence Allegro 16.3-S038*
G04 Origin Date:  Mon Jan 13 14:11:53 2014*
G04 *
G04 Layer:  DRAWING FORMAT/TITLE_BLOCK*
G04 Layer:  VIA CLASS/VCC1*
G04 Layer:  PIN/VCC1*
G04 Layer:  MANUFACTURING/PHOTOPLOT_OUTLINE*
G04 Layer:  ETCH/VCC1*
G04 Layer:  DRAWING FORMAT/TITLE_DATA_VCC1*
G04 *
G04 Offset:    (0.00 0.00)*
G04 Mirror:    No*
G04 Mode:      Negative*
G04 Rotation:  0*
G04 FullContactRelief:  No*
G04 UndefLineWidth:     6.00*
G04 ================== end FILE IDENTIFICATION RECORD ====================*
%FSLAX25Y25*MOIN*%
%IR0*IPPOS*OFA0.00000B0.00000*MIA0B0*SFA1.00000B1.00000*%
%ADD11C,.03*%
%ADD30C,.05*%
%ADD24C,.042*%
%ADD12C,.063*%
%ADD27C,.064*%
%ADD20C,.082*%
%ADD21C,.083*%
%ADD14C,.056*%
%ADD16C,.048*%
%ADD23C,.059*%
%ADD19C,.077*%
%AMMACRO13*
4,1,16,.02548,.01487,
.027675,.01022,
.029029,.005259,
.029501,.000138,
.029077,-.004987,
.027769,-.009961,
.025618,-.014631,
.02548,-.01487,
.03056,-.01996,
.033562,-.01435,
.035544,-.008304,
.036446,-.002006,
.03624,.004353,
.034934,.01058,
.032566,.016486,
.03056,.01996,
.02548,.01487,
90.*
4,1,16,.01487,-.02548,
.01022,-.027675,
.005259,-.029029,
.000138,-.029501,
-.004987,-.029077,
-.009961,-.027769,
-.014631,-.025618,
-.01487,-.02548,
-.01996,-.03056,
-.01435,-.033562,
-.008304,-.035544,
-.002006,-.036446,
.004353,-.03624,
.01058,-.034934,
.016486,-.032566,
.01996,-.03056,
.01487,-.02548,
90.*
4,1,16,-.02548,-.01487,
-.027675,-.01022,
-.029029,-.005259,
-.029501,-.000138,
-.029077,.004987,
-.027769,.009961,
-.025618,.014631,
-.02548,.01487,
-.03056,.01996,
-.033562,.01435,
-.035544,.008304,
-.036446,.002006,
-.03624,-.004353,
-.034934,-.01058,
-.032566,-.016486,
-.03056,-.01996,
-.02548,-.01487,
90.*
4,1,16,-.01487,.02548,
-.01022,.027675,
-.005259,.029029,
-.000138,.029501,
.004987,.029077,
.009961,.027769,
.014631,.025618,
.01487,.02548,
.01996,.03056,
.01435,.033562,
.008304,.035544,
.002006,.036446,
-.004353,.03624,
-.01058,.034934,
-.016486,.032566,
-.01996,.03056,
-.01487,.02548,
90.*
%
%ADD13MACRO13*%
%ADD34O,.235X.274*%
%ADD18C,.125*%
%ADD10C,.162*%
%ADD33C,.235*%
%ADD35C,.345*%
%ADD29C,.129*%
%ADD15C,.156*%
%AMMACRO17*
4,1,36,0.0,.013,
-.002257,.012803,
-.004446,.012216,
-.0065,.011258,
-.008356,.009959,
-.009959,.008356,
-.011258,.0065,
-.012216,.004446,
-.012803,.002257,
-.013,0.0,
-.012803,-.002257,
-.012216,-.004446,
-.011258,-.0065,
-.009959,-.008356,
-.008356,-.009959,
-.0065,-.011258,
-.004446,-.012216,
-.002257,-.012803,
0.0,-.013,
.002257,-.012803,
.004446,-.012216,
.0065,-.011258,
.008356,-.009959,
.009959,-.008356,
.011258,-.0065,
.012216,-.004446,
.012803,-.002257,
.013,0.0,
.012803,.002257,
.012216,.004446,
.011258,.0065,
.009959,.008356,
.008356,.009959,
.0065,.011258,
.004446,.012216,
.002257,.012803,
0.0,.013,
270.*
%
%ADD17MACRO17*%
%AMMACRO32*
4,1,36,0.0,.014,
.002431,.013787,
.004788,.013156,
.007,.012124,
.008999,.010725,
.010725,.008999,
.012124,.007,
.013156,.004788,
.013787,.002431,
.014,0.0,
.013787,-.002431,
.013156,-.004788,
.012124,-.007,
.010725,-.008999,
.008999,-.010725,
.007,-.012124,
.004788,-.013156,
.002431,-.013787,
0.0,-.014,
-.002431,-.013787,
-.004788,-.013156,
-.007,-.012124,
-.008999,-.010725,
-.010725,-.008999,
-.012124,-.007,
-.013156,-.004788,
-.013787,-.002431,
-.014,0.0,
-.013787,.002431,
-.013156,.004788,
-.012124,.007,
-.010725,.008999,
-.008999,.010725,
-.007,.012124,
-.004788,.013156,
-.002431,.013787,
0.0,.014,
180.*
%
%ADD32MACRO32*%
%ADD25C,.188*%
%AMMACRO26*
4,1,36,0.0,.004,
.000695,.003939,
.001368,.003759,
.002,.003464,
.002571,.003064,
.003064,.002571,
.003464,.002,
.003759,.001368,
.003939,.000695,
.004,0.0,
.003939,-.000695,
.003759,-.001368,
.003464,-.002,
.003064,-.002571,
.002571,-.003064,
.002,-.003464,
.001368,-.003759,
.000695,-.003939,
0.0,-.004,
-.000695,-.003939,
-.001368,-.003759,
-.002,-.003464,
-.002571,-.003064,
-.003064,-.002571,
-.003464,-.002,
-.003759,-.001368,
-.003939,-.000695,
-.004,0.0,
-.003939,.000695,
-.003759,.001368,
-.003464,.002,
-.003064,.002571,
-.002571,.003064,
-.002,.003464,
-.001368,.003759,
-.000695,.003939,
0.0,.004,
0.0*
%
%ADD26MACRO26*%
%AMMACRO28*
4,1,16,.02584,.01524,
.028094,.010521,
.029494,.005483,
.029998,.000278,
.029591,-.004935,
.028284,-.009999,
.026118,-.014758,
.02584,-.01524,
.03092,-.02032,
.033979,-.014642,
.036005,-.008519,
.036938,-.002138,
.036748,.004309,
.035441,.010625,
.033058,.016618,
.03092,.02032,
.02584,.01524,
270.*
4,1,16,.01524,-.02584,
.010521,-.028094,
.005483,-.029494,
.000278,-.029998,
-.004935,-.029591,
-.009999,-.028284,
-.014758,-.026118,
-.01524,-.02584,
-.02032,-.03092,
-.014642,-.033979,
-.008519,-.036005,
-.002138,-.036938,
.004309,-.036748,
.010625,-.035441,
.016618,-.033058,
.02032,-.03092,
.01524,-.02584,
270.*
4,1,16,-.02584,-.01524,
-.028094,-.010521,
-.029494,-.005483,
-.029998,-.000278,
-.029591,.004935,
-.028284,.009999,
-.026118,.014758,
-.02584,.01524,
-.03092,.02032,
-.033979,.014642,
-.036005,.008519,
-.036938,.002138,
-.036748,-.004309,
-.035441,-.010625,
-.033058,-.016618,
-.03092,-.02032,
-.02584,-.01524,
270.*
4,1,16,-.01524,.02584,
-.010521,.028094,
-.005483,.029494,
-.000278,.029998,
.004935,.029591,
.009999,.028284,
.014758,.026118,
.01524,.02584,
.02032,.03092,
.014642,.033979,
.008519,.036005,
.002138,.036938,
-.004309,.036748,
-.010625,.035441,
-.016618,.033058,
-.02032,.03092,
-.01524,.02584,
270.*
%
%ADD28MACRO28*%
%AMMACRO31*
4,1,15,.02291,.0123,
.024698,.008135,
.025735,.003723,
.025991,-.000803,
.025456,-.005304,
.024149,-.009644,
.02291,-.0123,
.02803,-.01742,
.030629,-.012288,
.032298,-.006783,
.032985,-.001071,
.03267,.004673,
.031362,.010275,
.029101,.015565,
.02803,.01742,
.02291,.0123,
180.*
4,1,15,.0123,-.02291,
.008135,-.024698,
.003723,-.025735,
-.000803,-.025991,
-.005304,-.025456,
-.009644,-.024149,
-.0123,-.02291,
-.01742,-.02803,
-.012288,-.030629,
-.006783,-.032298,
-.001071,-.032985,
.004673,-.03267,
.010275,-.031362,
.015565,-.029101,
.01742,-.02803,
.0123,-.02291,
180.*
4,1,15,-.02291,-.0123,
-.024698,-.008135,
-.025735,-.003723,
-.025991,.000803,
-.025456,.005304,
-.024149,.009644,
-.02291,.0123,
-.02803,.01742,
-.030629,.012288,
-.032298,.006783,
-.032985,.001071,
-.03267,-.004673,
-.031362,-.010275,
-.029101,-.015565,
-.02803,-.01742,
-.02291,-.0123,
180.*
4,1,15,-.0123,.02291,
-.008135,.024698,
-.003723,.025735,
.000803,.025991,
.005304,.025456,
.009644,.024149,
.0123,.02291,
.01742,.02803,
.012288,.030629,
.006783,.032298,
.001071,.032985,
-.004673,.03267,
-.010275,.031362,
-.015565,.029101,
-.01742,.02803,
-.0123,.02291,
180.*
%
%ADD31MACRO31*%
%AMMACRO22*
4,1,17,.03056,.01996,
.033562,.01435,
.035544,.008304,
.036446,.002006,
.03624,-.004353,
.034934,-.01058,
.032566,-.016486,
.03056,-.01996,
.0356,-.025,
.0394,-.018438,
.042004,-.011316,
.043331,-.003851,
.043341,.003732,
.042034,.011201,
.039451,.018331,
.035668,.024903,
.0356,.025,
.03056,.01996,
270.*
4,1,17,.01996,-.03056,
.01435,-.033562,
.008304,-.035544,
.002006,-.036446,
-.004353,-.03624,
-.01058,-.034934,
-.016486,-.032566,
-.01996,-.03056,
-.025,-.0356,
-.018438,-.0394,
-.011316,-.042004,
-.003851,-.043331,
.003732,-.043341,
.011201,-.042034,
.018331,-.039451,
.024903,-.035668,
.025,-.0356,
.01996,-.03056,
270.*
4,1,17,-.03056,-.01996,
-.033562,-.01435,
-.035544,-.008304,
-.036446,-.002006,
-.03624,.004353,
-.034934,.01058,
-.032566,.016486,
-.03056,.01996,
-.0356,.025,
-.0394,.018438,
-.042004,.011316,
-.043331,.003851,
-.043341,-.003732,
-.042034,-.011201,
-.039451,-.018331,
-.035668,-.024903,
-.0356,-.025,
-.03056,-.01996,
270.*
4,1,17,-.01996,.03056,
-.01435,.033562,
-.008304,.035544,
-.002006,.036446,
.004353,.03624,
.01058,.034934,
.016486,.032566,
.01996,.03056,
.025,.0356,
.018438,.0394,
.011316,.042004,
.003851,.043331,
-.003732,.043341,
-.011201,.042034,
-.018331,.039451,
-.024903,.035668,
-.025,.0356,
-.01996,.03056,
270.*
%
%ADD22MACRO22*%
%ADD36C,.006*%
%ADD39C,.08409*%
%ADD46C,.4138*%
%ADD40C,.24506*%
%ADD37C,.16406*%
%ADD42C,.13266*%
%ADD44C,.40492*%
%ADD47C,.41384*%
%ADD41C,.35606*%
%ADD38C,.15806*%
%ADD43C,.41386*%
%ADD45C,.41378*%
G75*
%LPD*%
G75*
G36*
G01X-723776Y-489221D02*
X1782976D01*
Y2987387D01*
X-723776D01*
Y-489221D01*
G37*
%LPC*%
G75*
G36*
G01X75838Y2066741D02*
G03X77828I995J1125D01*
G02X78159Y2066866I331J-375D01*
G01X92520D01*
G03X102425Y2076772I0J9905D01*
G01Y2080709D01*
G02X104331Y2082614I1906J-1D01*
G01X108657D01*
G02X108990Y2082487I0J-500D01*
G03X110992I1001J1120D01*
G02X111325Y2082614I333J-373D01*
G01X158657D01*
G02X158990Y2082487I0J-500D01*
G03X160992I1001J1120D01*
G02X161325Y2082614I333J-373D01*
G01X208657D01*
G02X208990Y2082487I0J-500D01*
G03X210992I1001J1120D01*
G02X211325Y2082614I333J-373D01*
G01X258657D01*
G02X258990Y2082487I0J-500D01*
G03X260992I1001J1120D01*
G02X261325Y2082614I333J-373D01*
G01X308657D01*
G02X308990Y2082487I0J-500D01*
G03X310992I1001J1120D01*
G02X311325Y2082614I333J-373D01*
G01X358657D01*
G02X358990Y2082487I0J-500D01*
G03X360992I1001J1120D01*
G02X361325Y2082614I333J-373D01*
G01X397638D01*
G02X401512Y2078740I0J-3874D01*
G01Y2068434D01*
G02X401387Y2068103I-500J0D01*
G03Y2066113I1125J-995D01*
G02X401512Y2065782I-375J-331D01*
G01Y2018434D01*
G02X401387Y2018103I-500J0D01*
G03Y2016113I1125J-995D01*
G02X401512Y2015782I-375J-331D01*
G01Y1968434D01*
G02X401387Y1968103I-500J0D01*
G03Y1966113I1125J-995D01*
G02X401512Y1965782I-375J-331D01*
G01Y1918434D01*
G02X401387Y1918103I-500J0D01*
G03Y1916113I1125J-995D01*
G02X401512Y1915782I-375J-331D01*
G01Y1868434D01*
G02X401387Y1868103I-500J0D01*
G03Y1866113I1125J-995D01*
G02X401512Y1865782I-375J-331D01*
G01Y1818434D01*
G02X401387Y1818103I-500J0D01*
G03Y1816113I1125J-995D01*
G02X401512Y1815782I-375J-331D01*
G01Y1768434D01*
G02X401387Y1768103I-500J0D01*
G03Y1766113I1125J-995D01*
G02X401512Y1765782I-375J-331D01*
G01Y1718434D01*
G02X401387Y1718103I-500J0D01*
G03Y1716113I1125J-995D01*
G02X401512Y1715782I-375J-331D01*
G01Y1668434D01*
G02X401387Y1668103I-500J0D01*
G03Y1666113I1125J-995D01*
G02X401512Y1665782I-375J-331D01*
G01Y1618434D01*
G02X401387Y1618103I-500J0D01*
G03Y1616113I1125J-995D01*
G02X401512Y1615782I-375J-331D01*
G01Y1568434D01*
G02X401387Y1568103I-500J0D01*
G03Y1566113I1125J-995D01*
G02X401512Y1565782I-375J-331D01*
G01Y1518434D01*
G02X401387Y1518103I-500J0D01*
G03Y1516113I1125J-995D01*
G02X401512Y1515782I-375J-331D01*
G01Y1468434D01*
G02X401387Y1468103I-500J0D01*
G03Y1466113I1125J-995D01*
G02X401512Y1465782I-375J-331D01*
G01Y1418434D01*
G02X401387Y1418103I-500J0D01*
G03Y1416113I1125J-995D01*
G02X401512Y1415782I-375J-331D01*
G01Y1368434D01*
G02X401387Y1368103I-500J0D01*
G03Y1366113I1125J-995D01*
G02X401512Y1365782I-375J-331D01*
G01Y1318434D01*
G02X401387Y1318103I-500J0D01*
G03Y1316113I1125J-995D01*
G02X401512Y1315782I-375J-331D01*
G01Y1268434D01*
G02X401387Y1268103I-500J0D01*
G03Y1266113I1125J-995D01*
G02X401512Y1265782I-375J-331D01*
G01Y1218434D01*
G02X401387Y1218103I-500J0D01*
G03Y1216113I1125J-995D01*
G02X401512Y1215782I-375J-331D01*
G01Y1168434D01*
G02X401387Y1168103I-500J0D01*
G03Y1166113I1125J-995D01*
G02X401512Y1165782I-375J-331D01*
G01Y1118434D01*
G02X401387Y1118103I-500J0D01*
G03Y1116113I1125J-995D01*
G02X401512Y1115782I-375J-331D01*
G01Y1068434D01*
G02X401387Y1068103I-500J0D01*
G03Y1066113I1125J-995D01*
G02X401512Y1065782I-375J-331D01*
G01Y1018434D01*
G02X401387Y1018103I-500J0D01*
G03Y1016113I1125J-995D01*
G02X401512Y1015782I-375J-331D01*
G01Y968434D01*
G02X401387Y968103I-500J0D01*
G03Y966113I1125J-995D01*
G02X401512Y965782I-375J-331D01*
G01Y918434D01*
G02X401387Y918103I-500J0D01*
G03Y916113I1125J-995D01*
G02X401512Y915782I-375J-331D01*
G01Y868434D01*
G02X401387Y868103I-500J0D01*
G03Y866113I1125J-995D01*
G02X401512Y865782I-375J-331D01*
G01Y818434D01*
G02X401387Y818103I-500J0D01*
G03Y816113I1125J-995D01*
G02X401512Y815782I-375J-331D01*
G01Y768434D01*
G02X401387Y768103I-500J0D01*
G03Y766113I1125J-995D01*
G02X401512Y765782I-375J-331D01*
G01Y718434D01*
G02X401387Y718103I-500J0D01*
G03Y716113I1125J-995D01*
G02X401512Y715782I-375J-331D01*
G01Y668434D01*
G02X401387Y668103I-500J0D01*
G03Y666113I1125J-995D01*
G02X401512Y665782I-375J-331D01*
G01Y618434D01*
G02X401387Y618103I-500J0D01*
G03Y616113I1125J-995D01*
G02X401512Y615782I-375J-331D01*
G01Y568434D01*
G02X401387Y568103I-500J0D01*
G03Y566113I1125J-995D01*
G02X401512Y565782I-375J-331D01*
G01Y518434D01*
G02X401387Y518103I-500J0D01*
G03Y516113I1125J-995D01*
G02X401512Y515782I-375J-331D01*
G01Y468434D01*
G02X401387Y468103I-500J0D01*
G03Y466113I1125J-995D01*
G02X401512Y465782I-375J-331D01*
G01Y418434D01*
G02X401387Y418103I-500J0D01*
G03Y416113I1125J-995D01*
G02X401512Y415782I-375J-331D01*
G01Y368434D01*
G02X401387Y368103I-500J0D01*
G03Y366113I1125J-995D01*
G02X401512Y365782I-375J-331D01*
G01Y318434D01*
G02X401387Y318103I-500J0D01*
G03Y316113I1125J-995D01*
G02X401512Y315782I-375J-331D01*
G01Y268434D01*
G02X401387Y268103I-500J0D01*
G03Y266113I1125J-995D01*
G02X401512Y265782I-375J-331D01*
G01Y218434D01*
G02X401387Y218103I-500J0D01*
G03Y216113I1125J-995D01*
G02X401512Y215782I-375J-331D01*
G01Y168434D01*
G02X401387Y168103I-500J0D01*
G03Y166113I1125J-995D01*
G02X401512Y165782I-375J-331D01*
G01Y118434D01*
G02X401387Y118103I-500J0D01*
G03Y116113I1125J-995D01*
G02X401512Y115782I-375J-331D01*
G01Y68434D01*
G02X401387Y68103I-500J0D01*
G03Y66113I1125J-995D01*
G02X401512Y65782I-375J-331D01*
G01Y18434D01*
G02X401387Y18103I-500J0D01*
G03Y16113I1125J-995D01*
G02X401512Y15782I-375J-331D01*
G01Y7874D01*
G02X397638Y4000I-3874J0D01*
G01X376547D01*
G02X376215Y4126I0J500D01*
G03X374223I-996J-1124D01*
G02X373891Y4000I-332J374D01*
G01X326547D01*
G02X326215Y4126I0J500D01*
G03X324223I-996J-1124D01*
G02X323891Y4000I-332J374D01*
G01X276547D01*
G02X276215Y4126I0J500D01*
G03X274223I-996J-1124D01*
G02X273891Y4000I-332J374D01*
G01X226547D01*
G02X226215Y4126I0J500D01*
G03X224223I-996J-1124D01*
G02X223891Y4000I-332J374D01*
G01X176547D01*
G02X176215Y4126I0J500D01*
G03X174223I-996J-1124D01*
G02X173891Y4000I-332J374D01*
G01X126547D01*
G02X126215Y4126I0J500D01*
G03X124223I-996J-1124D01*
G02X123891Y4000I-332J374D01*
G01X104331D01*
G02X102425Y5906I0J1906D01*
G01Y9843D01*
G03X92520Y19748I-9905J0D01*
G01X76549D01*
G02X76217Y19874I0J500D01*
G03X74221I-998J-1122D01*
G02X73889Y19748I-332J374D01*
G01X26549D01*
G02X26217Y19874I0J500D01*
G03X24221I-998J-1122D01*
G02X23889Y19748I-332J374D01*
G01X5906D01*
G02X4000Y21654I0J1906D01*
G01Y50707D01*
G02X4126Y51038I500J-1D01*
G03Y53030I-1125J996D01*
G02X4000Y53361I374J332D01*
G01Y98707D01*
G02X4126Y99038I500J-1D01*
G03Y101030I-1125J996D01*
G02X4000Y101361I374J332D01*
G01Y148707D01*
G02X4126Y149038I500J-1D01*
G03Y151030I-1125J996D01*
G02X4000Y151361I374J332D01*
G01Y198707D01*
G02X4126Y199038I500J-1D01*
G03Y201030I-1125J996D01*
G02X4000Y201361I374J332D01*
G01Y248707D01*
G02X4126Y249038I500J-1D01*
G03Y251030I-1125J996D01*
G02X4000Y251361I374J332D01*
G01Y298707D01*
G02X4126Y299038I500J-1D01*
G03Y301030I-1125J996D01*
G02X4000Y301361I374J332D01*
G01Y348707D01*
G02X4126Y349038I500J-1D01*
G03Y351030I-1125J996D01*
G02X4000Y351361I374J332D01*
G01Y398707D01*
G02X4126Y399038I500J-1D01*
G03Y401030I-1125J996D01*
G02X4000Y401361I374J332D01*
G01Y448707D01*
G02X4126Y449038I500J-1D01*
G03Y451030I-1125J996D01*
G02X4000Y451361I374J332D01*
G01Y498707D01*
G02X4126Y499038I500J-1D01*
G03Y501030I-1125J996D01*
G02X4000Y501361I374J332D01*
G01Y548707D01*
G02X4126Y549038I500J-1D01*
G03Y551030I-1125J996D01*
G02X4000Y551361I374J332D01*
G01Y598707D01*
G02X4126Y599038I500J-1D01*
G03Y601030I-1125J996D01*
G02X4000Y601361I374J332D01*
G01Y648707D01*
G02X4126Y649038I500J-1D01*
G03Y651030I-1125J996D01*
G02X4000Y651361I374J332D01*
G01Y698707D01*
G02X4126Y699038I500J-1D01*
G03Y701030I-1125J996D01*
G02X4000Y701361I374J332D01*
G01Y748707D01*
G02X4126Y749038I500J-1D01*
G03Y751030I-1125J996D01*
G02X4000Y751361I374J332D01*
G01Y798707D01*
G02X4126Y799038I500J-1D01*
G03Y801030I-1125J996D01*
G02X4000Y801361I374J332D01*
G01Y848707D01*
G02X4126Y849038I500J-1D01*
G03Y851030I-1125J996D01*
G02X4000Y851361I374J332D01*
G01Y898707D01*
G02X4126Y899038I500J-1D01*
G03Y901030I-1125J996D01*
G02X4000Y901361I374J332D01*
G01Y948707D01*
G02X4126Y949038I500J-1D01*
G03Y951030I-1125J996D01*
G02X4000Y951361I374J332D01*
G01Y998707D01*
G02X4126Y999038I500J-1D01*
G03Y1001030I-1125J996D01*
G02X4000Y1001361I374J332D01*
G01Y1048707D01*
G02X4126Y1049038I500J-1D01*
G03Y1051030I-1125J996D01*
G02X4000Y1051361I374J332D01*
G01Y1098707D01*
G02X4126Y1099038I500J-1D01*
G03Y1101030I-1125J996D01*
G02X4000Y1101361I374J332D01*
G01Y1148707D01*
G02X4126Y1149038I500J-1D01*
G03Y1151030I-1125J996D01*
G02X4000Y1151361I374J332D01*
G01Y1198707D01*
G02X4126Y1199038I500J-1D01*
G03Y1201030I-1125J996D01*
G02X4000Y1201361I374J332D01*
G01Y1248707D01*
G02X4126Y1249038I500J-1D01*
G03Y1251030I-1125J996D01*
G02X4000Y1251361I374J332D01*
G01Y1298707D01*
G02X4126Y1299038I500J-1D01*
G03Y1301030I-1125J996D01*
G02X4000Y1301361I374J332D01*
G01Y1348707D01*
G02X4126Y1349038I500J-1D01*
G03Y1351030I-1125J996D01*
G02X4000Y1351361I374J332D01*
G01Y1398707D01*
G02X4126Y1399038I500J-1D01*
G03Y1401030I-1125J996D01*
G02X4000Y1401361I374J332D01*
G01Y1448707D01*
G02X4126Y1449038I500J-1D01*
G03Y1451030I-1125J996D01*
G02X4000Y1451361I374J332D01*
G01Y1498707D01*
G02X4126Y1499038I500J-1D01*
G03Y1501030I-1125J996D01*
G02X4000Y1501361I374J332D01*
G01Y1548707D01*
G02X4126Y1549038I500J-1D01*
G03Y1551030I-1125J996D01*
G02X4000Y1551361I374J332D01*
G01Y1593269D01*
G02X4127Y1593602I500J0D01*
G03Y1595602I-1121J1000D01*
G02X4000Y1595935I373J333D01*
G01Y1608826D01*
G02X4128Y1609160I500J0D01*
G03Y1611170I-1116J1005D01*
G02X4000Y1611504I372J334D01*
G01Y1648707D01*
G02X4126Y1649038I500J-1D01*
G03Y1651030I-1125J996D01*
G02X4000Y1651361I374J332D01*
G01Y1698707D01*
G02X4126Y1699038I500J-1D01*
G03Y1701030I-1125J996D01*
G02X4000Y1701361I374J332D01*
G01Y1748707D01*
G02X4126Y1749038I500J-1D01*
G03Y1751030I-1125J996D01*
G02X4000Y1751361I374J332D01*
G01Y1798707D01*
G02X4126Y1799038I500J-1D01*
G03Y1801030I-1125J996D01*
G02X4000Y1801361I374J332D01*
G01Y1848707D01*
G02X4126Y1849038I500J-1D01*
G03Y1851030I-1125J996D01*
G02X4000Y1851361I374J332D01*
G01Y1898707D01*
G02X4126Y1899038I500J-1D01*
G03Y1901030I-1125J996D01*
G02X4000Y1901361I374J332D01*
G01Y1948707D01*
G02X4126Y1949038I500J-1D01*
G03Y1951030I-1125J996D01*
G02X4000Y1951361I374J332D01*
G01Y1998707D01*
G02X4126Y1999038I500J-1D01*
G03Y2001030I-1125J996D01*
G02X4000Y2001361I374J332D01*
G01Y2048707D01*
G02X4126Y2049038I500J-1D01*
G03Y2051030I-1125J996D01*
G02X4000Y2051361I374J332D01*
G01Y2064961D01*
G02X5905Y2066866I1905J0D01*
G01X25507D01*
G02X25838Y2066741I0J-500D01*
G03X27828I995J1125D01*
G02X28159Y2066866I331J-375D01*
G01X75507D01*
G02X75838Y2066741I0J-500D01*
G37*
%LPD*%
G75*
G36*
G01X17980Y1347510D02*
Y1348455D01*
X17981D01*
G02X22973Y1348450I2490J-5857D01*
G01X22974D01*
Y1347505D01*
G03X23213Y1347078I500J0D01*
G02X23859Y1346612I-2741J-4480D01*
G01X25411D01*
X25412Y1346611D01*
G02X14107Y1342598I-4940J-4013D01*
G02X15507Y1346580I6365J-1D01*
G01X17048D01*
G02X17740Y1347083I3424J-3982D01*
G03X17980Y1347510I-260J427D01*
G37*
G36*
G01X17976Y989245D02*
Y990190D01*
X17977D01*
G02X22969Y990185I2490J-5857D01*
G01X22970D01*
Y989240D01*
G03X23209Y988813I500J0D01*
G02X23856Y988346I-2741J-4480D01*
G01X25408D01*
G02X14103Y984333I-4940J-4013D01*
G02X15503Y988316I6365J0D01*
G01X17045D01*
G02X17736Y988818I3422J-3984D01*
G03X17976Y989245I-260J427D01*
G37*
G36*
G01X170004Y727205D02*
G02X156767Y727182I-6619J0D01*
G02X169983Y727726I6618J30D01*
G02X169986Y727689I-6594J-553D01*
G02X170004Y727205I-6600J-488D01*
G37*
G36*
G01Y552205D02*
G02X156767Y552182I-6619J0D01*
G02X169983Y552726I6618J30D01*
G02X169986Y552689I-6594J-553D01*
G02X170004Y552205I-6600J-488D01*
G37*
G36*
G01X292850Y1881102D02*
Y1885039D01*
G02X321322I14236J0D01*
G01Y1881102D01*
G02X292850I-14236J0D01*
G37*
G36*
G01X169982Y1952727D02*
G02X170003Y1952205I-6597J-527D01*
G02X156766I-6618J0D01*
G02X169982Y1952727I6618J0D01*
G37*
G36*
G01Y1777727D02*
G02X170003Y1777205I-6597J-527D01*
G02X156766I-6618J0D01*
G02X169982Y1777727I6618J0D01*
G37*
G36*
G01Y1602727D02*
G02X170003Y1602205I-6597J-527D01*
G02X156766I-6618J0D01*
G02X169982Y1602727I6618J0D01*
G37*
G36*
G01Y1427727D02*
G02X170003Y1427205I-6597J-527D01*
G02X156766I-6618J0D01*
G02X169982Y1427727I6618J0D01*
G37*
G36*
G01Y1252727D02*
G02X170003Y1252205I-6597J-527D01*
G02X156766I-6618J0D01*
G02X169982Y1252727I6618J0D01*
G37*
G36*
G01Y1077727D02*
G02X170003Y1077205I-6597J-527D01*
G02X156766I-6618J0D01*
G02X169982Y1077727I6618J0D01*
G37*
G36*
G01X26828Y1054605D02*
G02X20471Y1060962I-6357J0D01*
G01Y1060963D01*
X20472D01*
G02X26828Y1054605I-1J-6357D01*
G37*
G36*
G01X169982Y902727D02*
G02X170003Y902205I-6597J-527D01*
G02X156766I-6618J0D01*
G02X169982Y902727I6618J0D01*
G37*
G36*
G01Y377727D02*
G02X170002Y377205I-6597J-514D01*
G02X156766I-6618J0D01*
G02X169982Y377727I6618J0D01*
G37*
G36*
G01Y202727D02*
G02X170002Y202205I-6597J-514D01*
G02X156766I-6618J0D01*
G02X169982Y202727I6618J0D01*
G37*
G36*
G01Y27727D02*
G02X170002Y27205I-6597J-514D01*
G02X156766I-6618J0D01*
G02X169982Y27727I6618J0D01*
G37*
G54D39*
X30473Y102007D03*
Y137440D03*
X30197Y305027D03*
Y352271D03*
X30473Y1855008D03*
Y1890441D03*
Y1937007D03*
Y1972440D03*
Y2012007D03*
Y2047440D03*
G54D46*
X65354Y814960D03*
Y1514960D03*
G54D40*
X307086Y308267D03*
G54D37*
X29979Y30500D03*
Y75500D03*
Y166500D03*
Y211500D03*
Y239500D03*
Y284500D03*
Y375500D03*
Y420500D03*
G54D42*
X373385Y32520D03*
Y207520D03*
Y382520D03*
X373386Y557520D03*
Y732520D03*
X373385Y907520D03*
Y1082520D03*
Y1257520D03*
Y1432520D03*
Y1607520D03*
Y1782520D03*
Y1957520D03*
G54D44*
X307086Y127164D03*
X307088Y477164D03*
X307087Y827164D03*
Y1343503D03*
Y1693503D03*
Y2043503D03*
G54D47*
X65354Y1164960D03*
G54D41*
X359842Y78780D03*
Y253780D03*
Y428779D03*
Y603779D03*
Y778780D03*
Y953780D03*
Y1128779D03*
Y1303780D03*
Y1478780D03*
Y1653780D03*
Y1828779D03*
Y2003780D03*
G54D38*
X30254Y514500D03*
Y559500D03*
Y1572504D03*
Y1617504D03*
G54D43*
X65354Y114960D03*
G54D45*
Y464960D03*
Y1864960D03*
G54D11*
X25219Y18752D03*
X3001Y52034D03*
Y100034D03*
Y150034D03*
Y200034D03*
Y250034D03*
Y300034D03*
Y350034D03*
Y400034D03*
Y450034D03*
Y500034D03*
X13441Y495961D03*
X3001Y550034D03*
X10914Y578848D03*
X15984Y578849D03*
X3001Y600034D03*
Y650034D03*
Y700034D03*
Y750034D03*
Y800034D03*
Y850034D03*
Y900034D03*
Y950034D03*
Y1000034D03*
Y1050034D03*
Y1100034D03*
Y1150034D03*
Y1200034D03*
Y1250034D03*
Y1300034D03*
Y1350034D03*
Y1400034D03*
Y1450034D03*
Y1500034D03*
Y1550034D03*
X11541Y1562330D03*
X3006Y1594602D03*
X3012Y1610165D03*
X3001Y1650034D03*
X11153Y1638435D03*
X16552Y1638005D03*
X3001Y1700034D03*
Y1750034D03*
Y1800034D03*
Y1850034D03*
Y1900034D03*
Y1950034D03*
Y2000034D03*
Y2050034D03*
X48433Y866179D03*
X48467Y869278D03*
X49441Y1238962D03*
X45581Y1278420D03*
X45413Y1283724D03*
X45244Y1289067D03*
X45350Y1299697D03*
X45267Y1294203D03*
X45281Y1310893D03*
X45244Y1305787D03*
X46980Y1335843D03*
Y1325843D03*
Y1315843D03*
Y1320843D03*
Y1330843D03*
Y1345843D03*
Y1340843D03*
X26833Y2067866D03*
X61888Y666012D03*
X57124Y675327D03*
X54483Y679810D03*
X59236Y670758D03*
X70865Y872278D03*
Y866278D03*
Y860278D03*
Y897750D03*
Y890116D03*
X60815Y1019026D03*
X63577Y1019115D03*
X57458Y1253378D03*
X54543Y1296513D03*
X63061Y1296312D03*
X67568Y1296654D03*
X61866Y1309190D03*
X54543Y1308995D03*
X67568Y1307829D03*
X54130Y1313763D03*
X70340Y1328203D03*
X61866Y1342104D03*
X55544Y1770835D03*
X55080Y1762982D03*
X54948Y1755171D03*
X56425Y1778371D03*
X70376Y1796383D03*
X75219Y18752D03*
X97417Y32853D03*
Y37438D03*
X97536Y376580D03*
X97457Y371909D03*
X97985Y391220D03*
X97643Y396024D03*
X93223Y417736D03*
X94347Y421562D03*
X86187Y680710D03*
X79520Y682439D03*
X88681Y704108D03*
X81563Y705437D03*
X86673Y685710D03*
X79536D03*
X96308Y696622D03*
X98591Y720745D03*
X98564Y715937D03*
X97443Y739962D03*
X97534Y735248D03*
X98124Y745139D03*
X95775Y751469D03*
X89338Y878294D03*
X91733Y899382D03*
X92633Y907404D03*
X91294Y926951D03*
X98139Y990959D03*
X76446Y1014871D03*
X79499D03*
X96904Y1067515D03*
X82763Y1060051D03*
X96948Y1092036D03*
X96949Y1087095D03*
X96774Y1072226D03*
X96684Y1081791D03*
X96510Y1395382D03*
X97403Y1424340D03*
X97825Y1419492D03*
X96993Y1443743D03*
X96996Y1438980D03*
X97465Y1447919D03*
X95236Y1453321D03*
X88837Y1771103D03*
X91460Y1765062D03*
X93771Y1748227D03*
X80376Y1772098D03*
Y1768566D03*
X75376Y1796236D03*
X80376Y1796163D03*
X85376Y1796236D03*
X80376Y1775609D03*
X76833Y2067866D03*
X106335Y22580D03*
X106958Y26285D03*
X108082Y38899D03*
X102646Y49461D03*
X101430Y41803D03*
X107405Y49898D03*
X107037Y34687D03*
X104350Y62293D03*
X107263Y72244D03*
X109054Y58250D03*
X104116Y82557D03*
X108672Y86150D03*
X106836Y376461D03*
X106709Y391219D03*
X105451Y406795D03*
X114498Y396207D03*
X101990Y426104D03*
X109475Y434743D03*
X111017Y419566D03*
X102960Y672823D03*
X113018Y706356D03*
X107025Y725368D03*
X105087Y754126D03*
X106935Y745139D03*
X107173Y735219D03*
X101244Y774100D03*
X112836Y769122D03*
X111967Y795261D03*
X115139Y849240D03*
X105395Y972040D03*
X102611Y972220D03*
X100687Y999391D03*
X107351Y1093484D03*
X107235Y1081791D03*
X107215Y1072208D03*
X98652Y1096403D03*
X108779Y1105760D03*
X105152Y1118381D03*
X112503Y1115860D03*
X105684Y1125919D03*
X108468Y1129286D03*
X100719Y1312810D03*
Y1306810D03*
Y1330810D03*
Y1336810D03*
Y1324810D03*
Y1318810D03*
Y1346065D03*
X106962Y1434041D03*
X106921Y1419492D03*
X106763Y1444599D03*
X107006Y1452651D03*
X105455Y1472894D03*
X108574Y1463389D03*
X113518Y1489571D03*
X99103Y1765722D03*
X99068Y1760827D03*
X107355Y1770437D03*
X99047Y1785571D03*
X98873Y1780542D03*
X99294Y1789947D03*
X107391Y1794460D03*
X107220Y1791589D03*
X107373Y1780544D03*
X105669Y1815227D03*
X108819Y1812118D03*
X106819Y1802230D03*
X108819Y1824470D03*
X109991Y2083607D03*
X125219Y3002D03*
X144878Y1738861D03*
X162384Y56744D03*
X157558Y51426D03*
X161742Y72497D03*
X162586Y68130D03*
X159417Y91281D03*
X158901Y85017D03*
X169500Y126110D03*
Y118626D03*
Y111407D03*
X166500D03*
Y118626D03*
Y126110D03*
X169329Y140623D03*
X169500Y132705D03*
X169329Y148066D03*
X166329D03*
X166500Y132705D03*
X166329Y140623D03*
X169329Y156102D03*
Y163621D03*
X166329D03*
Y156102D03*
X161377Y407575D03*
X156865Y401207D03*
X161257Y420869D03*
X159019Y439268D03*
X158807Y432969D03*
X159430Y461714D03*
X156430D03*
X159430Y483012D03*
X159259Y490930D03*
X159430Y468933D03*
Y476417D03*
X156430D03*
Y468933D03*
X156259Y490930D03*
X156430Y483012D03*
X159259Y513928D03*
Y498373D03*
Y506409D03*
X156259D03*
Y498373D03*
Y513928D03*
X156610Y751063D03*
X161826Y756757D03*
X161131Y774878D03*
X161644Y764231D03*
X158956Y780982D03*
X159053Y787280D03*
X158444Y822725D03*
X165872D03*
X162872D03*
X155444D03*
X165872Y830209D03*
X158444D03*
X165872Y836804D03*
X158444D03*
X165701Y844722D03*
X158273D03*
X165701Y852165D03*
X158273D03*
X155273D03*
X162701D03*
X155273Y844722D03*
X162701D03*
X155444Y836804D03*
X162872D03*
X155444Y830209D03*
X162872D03*
X165701Y860201D03*
X158273D03*
X165701Y867720D03*
X158273D03*
X155273D03*
X162701D03*
X155273Y860201D03*
X162701D03*
X164539Y1116135D03*
X162140Y1106853D03*
X156854Y1101031D03*
X159382Y1136151D03*
X158456Y1129045D03*
X156124Y1176256D03*
X163552D03*
Y1183740D03*
Y1190335D03*
X156124D03*
Y1183740D03*
X163552Y1169037D03*
X156124D03*
X153124D03*
X160552D03*
X153124Y1183740D03*
Y1190335D03*
X160552D03*
Y1183740D03*
Y1176256D03*
X153124D03*
X169375Y1183740D03*
Y1190335D03*
Y1176256D03*
X163381Y1198253D03*
X155953D03*
X152953D03*
X160381D03*
X169204D03*
X158618Y1399448D03*
X164037Y1400226D03*
X170351Y1401324D03*
X159192Y1451105D03*
X163099Y1457084D03*
X162524Y1462651D03*
X162242Y1471380D03*
X159216Y1477124D03*
X154109Y1499221D03*
X161537D03*
Y1506440D03*
X170360D03*
X154109D03*
X157109D03*
X164537D03*
Y1499221D03*
X157109D03*
X159526Y1483434D03*
X153938Y1528437D03*
X154109Y1513924D03*
Y1520519D03*
X170360Y1513924D03*
Y1520519D03*
X161537D03*
Y1513924D03*
X161366Y1528437D03*
X170189D03*
X164366D03*
X164537Y1513924D03*
Y1520519D03*
X157109D03*
Y1513924D03*
X156938Y1528437D03*
X153938Y1535880D03*
Y1543916D03*
Y1551435D03*
X170189Y1535880D03*
Y1543916D03*
X161366Y1535880D03*
Y1543916D03*
Y1551435D03*
X170189D03*
X164366D03*
Y1543916D03*
Y1535880D03*
X156938Y1551435D03*
Y1543916D03*
Y1535880D03*
X163257Y1737619D03*
X150309Y1737009D03*
X168151Y1739208D03*
X165782Y1732903D03*
X156183Y1735240D03*
X163250Y1815631D03*
X162140Y1807740D03*
X156452Y1800821D03*
X159822Y1831380D03*
X159075Y1825087D03*
X155091Y1866003D03*
X162519D03*
X159519D03*
X152091D03*
X155091Y1880706D03*
Y1887301D03*
X162519D03*
Y1880706D03*
Y1873222D03*
X155091D03*
X152091D03*
X168342D03*
X159519D03*
Y1880706D03*
Y1887301D03*
X168342D03*
Y1880706D03*
X152091Y1887301D03*
Y1880706D03*
X154920Y1902662D03*
Y1910698D03*
X162348Y1902662D03*
Y1910698D03*
X154920Y1895219D03*
X162348D03*
X168171D03*
X159348D03*
X151920D03*
X159348Y1910698D03*
Y1902662D03*
X168171Y1910698D03*
Y1902662D03*
X151920Y1910698D03*
Y1902662D03*
X154920Y1918217D03*
X162348D03*
X168171D03*
X159348D03*
X151920D03*
X159991Y2083607D03*
X175219Y3002D03*
X176928Y126110D03*
Y118626D03*
Y111407D03*
X173928D03*
Y118626D03*
Y126110D03*
X176757Y140623D03*
X176928Y132705D03*
X176757Y148066D03*
X173757D03*
X173928Y132705D03*
X173757Y140623D03*
X176757Y156102D03*
Y163621D03*
X173757D03*
Y156102D03*
X175033Y261594D03*
Y268813D03*
X178033D03*
Y261594D03*
X175033Y282892D03*
X174862Y290810D03*
Y298253D03*
X175033Y276297D03*
X178033D03*
X177862Y298253D03*
Y290810D03*
X178033Y282892D03*
X174862Y313808D03*
Y306289D03*
X177862D03*
Y313808D03*
X182191Y822725D03*
X174695D03*
X171695D03*
X179191D03*
X174524Y844722D03*
Y852165D03*
X182191Y830209D03*
X174695D03*
X182191Y836804D03*
X174695D03*
X182020Y844722D03*
Y852165D03*
X179020D03*
Y844722D03*
X171695Y836804D03*
X179191D03*
X171695Y830209D03*
X179191D03*
X171524Y852165D03*
Y844722D03*
X174524Y860201D03*
Y867720D03*
X182020Y860201D03*
Y867720D03*
X179020D03*
Y860201D03*
X171524Y867720D03*
Y860201D03*
X184284Y948331D03*
X175989Y944537D03*
X176011Y936829D03*
X184196Y967371D03*
X175359Y963486D03*
X175561Y955964D03*
X175135Y972490D03*
X184632Y983423D03*
X175022Y980281D03*
X175742Y989958D03*
X175449Y997660D03*
X184353Y1001556D03*
X184118Y1019280D03*
X188385Y1020810D03*
X175698Y1008730D03*
X175473Y1016296D03*
X175448Y1031766D03*
X175897Y1023997D03*
X179871Y1176256D03*
Y1190335D03*
Y1183740D03*
X172375Y1176256D03*
Y1190335D03*
Y1183740D03*
X176871D03*
Y1190335D03*
Y1176256D03*
X179700Y1198253D03*
X172204D03*
X176700D03*
X176083Y1402321D03*
X177856Y1506440D03*
X173360D03*
X180856D03*
X177856Y1513924D03*
Y1520519D03*
X177685Y1528437D03*
X173189D03*
X173360Y1520519D03*
Y1513924D03*
X180685Y1528437D03*
X180856Y1520519D03*
Y1513924D03*
X177685Y1535880D03*
Y1543916D03*
Y1551435D03*
X173189D03*
Y1543916D03*
Y1535880D03*
X180685Y1551435D03*
Y1543916D03*
Y1535880D03*
X173394Y1736051D03*
X178838Y1880706D03*
Y1887301D03*
Y1873222D03*
X171342Y1880706D03*
Y1887301D03*
Y1873222D03*
X175838D03*
Y1887301D03*
Y1880706D03*
X178667Y1902662D03*
Y1910698D03*
Y1895219D03*
X171171Y1902662D03*
Y1910698D03*
Y1895219D03*
X175667D03*
Y1910698D03*
Y1902662D03*
X178667Y1918217D03*
X171171D03*
X175667D03*
X219131Y1663167D03*
Y1670386D03*
Y1684465D03*
Y1677870D03*
X218960Y1692383D03*
Y1699826D03*
Y1707862D03*
Y1715381D03*
X209991Y2083607D03*
X225219Y3002D03*
X237955Y56999D03*
X240955D03*
X237955Y64483D03*
X237784Y78996D03*
X237955Y71078D03*
X240955D03*
X240784Y78996D03*
X240955Y64483D03*
X237784Y94475D03*
Y101994D03*
Y86439D03*
X240784D03*
Y101994D03*
Y94475D03*
X241033Y244995D03*
X233537D03*
X224714Y237776D03*
Y244995D03*
X227714D03*
Y237776D03*
X236537Y244995D03*
X241033Y259074D03*
X240862Y266992D03*
Y274435D03*
X241033Y252479D03*
X233537Y259074D03*
X233366Y266992D03*
Y274435D03*
X224714Y259074D03*
X224543Y266992D03*
Y274435D03*
X233537Y252479D03*
X224714D03*
X227714D03*
X236537D03*
X227543Y274435D03*
Y266992D03*
X227714Y259074D03*
X236366Y274435D03*
Y266992D03*
X236537Y259074D03*
X240862Y289990D03*
Y282471D03*
X233366Y289990D03*
X224543D03*
X233366Y282471D03*
X224543D03*
X227543D03*
X236366D03*
X227543Y289990D03*
X236366D03*
X229548Y461083D03*
X232548D03*
X238371Y482381D03*
X238200Y490299D03*
X229548Y482381D03*
X229377Y490299D03*
X238371Y468302D03*
Y475786D03*
X229548Y468302D03*
Y475786D03*
X232548D03*
Y468302D03*
X241371Y475786D03*
Y468302D03*
X232377Y490299D03*
X232548Y482381D03*
X241200Y490299D03*
X241371Y482381D03*
X238200Y513297D03*
X229377D03*
X238200Y497742D03*
X229377D03*
X238200Y505778D03*
X229377D03*
X232377D03*
X241200D03*
X232377Y497742D03*
X241200D03*
X232377Y513297D03*
X241200D03*
X227963Y608108D03*
X235391D03*
X227963Y601513D03*
X235391D03*
Y594029D03*
X227963D03*
X230963D03*
X238391D03*
Y601513D03*
X230963D03*
X238391Y608108D03*
X230963D03*
X227792Y631505D03*
X235220D03*
X227792Y623469D03*
X235220D03*
X227792Y616026D03*
X235220D03*
X238220D03*
X230792D03*
X238220Y623469D03*
X230792D03*
X238220Y631505D03*
X230792D03*
X227792Y639024D03*
X235220D03*
X238220D03*
X230792D03*
X231339Y959673D03*
X238767D03*
Y967157D03*
Y973752D03*
X231339D03*
Y967157D03*
X238767Y952454D03*
X231339D03*
X234339D03*
X241767D03*
X234339Y967157D03*
Y973752D03*
X241767D03*
Y967157D03*
Y959673D03*
X234339D03*
X238596Y981670D03*
X231168D03*
X238596Y997149D03*
Y989113D03*
X231168Y997149D03*
Y989113D03*
X234168D03*
Y997149D03*
X241596Y989113D03*
Y997149D03*
X234168Y981670D03*
X241596D03*
X238596Y1004668D03*
X231168D03*
X234168D03*
X241596D03*
X235659Y1215296D03*
X228231D03*
X235659Y1207777D03*
Y1199741D03*
X228231Y1207777D03*
Y1199741D03*
X231231D03*
Y1207777D03*
X238659Y1199741D03*
Y1207777D03*
X231231Y1215296D03*
X238659D03*
X235382Y1670386D03*
X226559Y1663167D03*
Y1670386D03*
X222131D03*
X229559D03*
Y1663167D03*
X238382Y1670386D03*
X222131Y1663167D03*
X242878Y1670386D03*
X235382Y1677870D03*
X235211Y1692383D03*
X235382Y1684465D03*
X226559D03*
Y1677870D03*
X226388Y1692383D03*
X221960D03*
X222131Y1677870D03*
Y1684465D03*
X229388Y1692383D03*
X229559Y1677870D03*
Y1684465D03*
X238382D03*
X238211Y1692383D03*
X238382Y1677870D03*
X242878D03*
Y1684465D03*
X242707Y1692383D03*
X235211Y1699826D03*
X226388D03*
X235211Y1715381D03*
Y1707862D03*
X226388D03*
Y1715381D03*
X221960D03*
Y1707862D03*
X229388Y1715381D03*
Y1707862D03*
X238211D03*
Y1715381D03*
X221960Y1699826D03*
X229388D03*
X238211D03*
X242707D03*
Y1707862D03*
Y1715381D03*
X245451Y56999D03*
X248451D03*
X245451Y64483D03*
X245280Y78996D03*
X245451Y71078D03*
X248451D03*
X248280Y78996D03*
X248451Y64483D03*
X245280Y94475D03*
Y101994D03*
Y86439D03*
X248280D03*
Y101994D03*
Y94475D03*
X267627Y115559D03*
X256947Y128276D03*
X257125Y115559D03*
X267420Y147540D03*
X263086Y147675D03*
X244033Y244995D03*
Y252479D03*
X243862Y274435D03*
Y266992D03*
X244033Y259074D03*
X243862Y282471D03*
Y289990D03*
X265722Y463102D03*
X245867Y482381D03*
X245696Y490299D03*
X245867Y468302D03*
Y475786D03*
X248867D03*
Y468302D03*
X248696Y490299D03*
X248867Y482381D03*
X265737Y473680D03*
X245696Y513297D03*
Y497742D03*
Y505778D03*
X248696D03*
Y497742D03*
Y513297D03*
X264516Y497341D03*
X251710Y608108D03*
Y601513D03*
Y594029D03*
X244214Y608108D03*
Y601513D03*
Y594029D03*
X247214D03*
Y601513D03*
Y608108D03*
X254710Y594029D03*
Y601513D03*
Y608108D03*
X264433Y624321D03*
X267433D03*
X251539Y631505D03*
Y623469D03*
Y616026D03*
X244043Y631505D03*
Y623469D03*
Y616026D03*
X247043D03*
Y623469D03*
Y631505D03*
X254539Y616026D03*
Y623469D03*
Y631505D03*
X251539Y639024D03*
X244043D03*
X247043D03*
X254539D03*
X255837Y823626D03*
X255687Y812192D03*
X264181Y847354D03*
X255086Y959673D03*
Y973752D03*
Y967157D03*
X247590Y959673D03*
Y973752D03*
Y967157D03*
X250590D03*
Y973752D03*
Y959673D03*
X258086Y967157D03*
Y973752D03*
Y959673D03*
X254915Y981670D03*
Y997149D03*
Y989113D03*
X247419Y981670D03*
Y997149D03*
Y989113D03*
X250419D03*
Y997149D03*
Y981670D03*
X257915Y989113D03*
Y997149D03*
Y981670D03*
X254915Y1004668D03*
X247419D03*
X250419D03*
X257915D03*
X267194Y1191777D03*
X262559D03*
X251978Y1215296D03*
X244482D03*
X251978Y1207777D03*
Y1199741D03*
X244482Y1207777D03*
Y1199741D03*
X247482D03*
Y1207777D03*
X254978Y1199741D03*
Y1207777D03*
X247482Y1215296D03*
X254978D03*
X245878Y1670386D03*
X245707Y1692383D03*
X245878Y1684465D03*
Y1677870D03*
X245707Y1715381D03*
Y1707862D03*
Y1699826D03*
X259991Y2083607D03*
X275219Y3002D03*
X276523Y147585D03*
X271943Y147630D03*
X271547Y260353D03*
X276617Y256400D03*
X281193Y256624D03*
X285513Y322688D03*
X281074D03*
X289895D03*
X281569Y436169D03*
X286665Y432844D03*
X291002D03*
X274991Y463099D03*
X277776Y497341D03*
X273405D03*
X268938D03*
X285348Y610540D03*
X290984Y607215D03*
X276044Y624627D03*
X279044D03*
X274514Y672192D03*
X270109D03*
X283340D03*
X278955D03*
X273114Y785968D03*
X278184Y782643D03*
X282737D03*
X270070Y812192D03*
X268686Y847488D03*
X277788Y847237D03*
X273305D03*
X285966Y959767D03*
X291194Y956442D03*
X285666Y1016162D03*
X281124D03*
X290107D03*
X282958Y1134471D03*
X288188Y1131146D03*
X276807Y1191777D03*
X272082D03*
X283808Y1308959D03*
X289210Y1305634D03*
X284240Y1374544D03*
X279518Y1374543D03*
X275052Y1374715D03*
X270579Y1374626D03*
X275521Y1479435D03*
X279990D03*
X270234Y1482760D03*
X291054Y1543211D03*
X284086Y1659883D03*
X289421Y1656558D03*
X279703Y1723398D03*
X284583Y1723465D03*
X289499Y1723735D03*
X274704Y1723196D03*
X281066Y1834569D03*
X291550Y1829846D03*
X286623Y1829400D03*
X280240Y1858668D03*
X279976Y1864565D03*
X287121Y1898327D03*
X282717D03*
X278262D03*
X273817D03*
X299687Y78778D03*
X304151D03*
X308651D03*
X313089D03*
X294483Y82732D03*
X308057Y248863D03*
X306267Y241010D03*
X314914Y238162D03*
X314940Y252083D03*
X294506Y322688D03*
X295509Y607215D03*
X295874Y956442D03*
X294617Y1016162D03*
X309678Y1053262D03*
X292698Y1131146D03*
X312527Y1162266D03*
X312698Y1172804D03*
X294133Y1305634D03*
X314183Y1403423D03*
X313894Y1513883D03*
X302267Y1524401D03*
X301734Y1513883D03*
X304870Y1543211D03*
X300392D03*
X295675D03*
X312077Y1575871D03*
X294090Y1656558D03*
X293606Y1858668D03*
X314562Y2009087D03*
X309991Y2083607D03*
X325219Y3002D03*
X331403Y51409D03*
X333889Y56021D03*
X338227Y61559D03*
X322005Y78778D03*
X317567D03*
X320372Y225979D03*
X318088Y231820D03*
X321899Y238137D03*
X331046Y232021D03*
X320961Y250105D03*
X324709Y231580D03*
X335522Y404033D03*
X323313Y418313D03*
X326196Y413982D03*
X328950Y409216D03*
X320980Y423225D03*
X336617Y577978D03*
X319305Y582111D03*
X329636Y584715D03*
X317724Y588250D03*
X337387Y586230D03*
X320380Y576491D03*
X331867Y589810D03*
X333750Y595326D03*
X321742Y599041D03*
X331568Y752967D03*
X339012Y752859D03*
X329336Y762693D03*
X334010Y758588D03*
X327524Y758020D03*
X329938Y948756D03*
X332527Y943746D03*
X324098Y946104D03*
X318557Y941178D03*
X323868Y929978D03*
X326646Y939788D03*
X336160Y937262D03*
X328583Y933262D03*
X321425Y951577D03*
X324246Y1051786D03*
X335677Y1048904D03*
X317592Y1053050D03*
X337509Y1109598D03*
X328989Y1121090D03*
X326558Y1126368D03*
X325796Y1162266D03*
X327452Y1279447D03*
X321978Y1282086D03*
X329619Y1284016D03*
X327932Y1289221D03*
X325636Y1399114D03*
X334646Y1400804D03*
X323720Y1570924D03*
X333474Y1566686D03*
X335963Y1573797D03*
X323813Y1753231D03*
X329887Y1752081D03*
X332399Y1926787D03*
X324803Y2005272D03*
X320045Y2005215D03*
X359931Y52189D03*
X348289Y50863D03*
X345089Y56190D03*
X340373Y51579D03*
X361799Y311938D03*
X362236Y324983D03*
X342097Y401684D03*
X363825Y401768D03*
X342900Y580126D03*
X354000Y652170D03*
X356559Y675167D03*
X362577Y752783D03*
X344109Y751809D03*
X343656Y933725D03*
X345578Y1047844D03*
X344099Y1106798D03*
X363169Y1329686D03*
X351391D03*
X354391D03*
X363169Y1350706D03*
Y1360043D03*
Y1340201D03*
X351391Y1350706D03*
Y1360043D03*
Y1340201D03*
X354391D03*
Y1360043D03*
Y1350706D03*
X363169Y1376210D03*
Y1367771D03*
X351391Y1376210D03*
Y1367771D03*
X354391D03*
Y1376210D03*
X344130Y1401670D03*
X350690Y1403243D03*
X348710Y1570187D03*
X361011Y1568890D03*
X343402Y1572080D03*
X348245Y1575241D03*
X355364Y1570990D03*
X352337Y1887285D03*
X345537Y1916558D03*
X344402Y1911123D03*
X363361Y1918313D03*
X358318Y1920680D03*
X363411Y1923459D03*
X340336Y1922409D03*
X359991Y2083607D03*
X375219Y3002D03*
X372204Y56126D03*
X379257Y52158D03*
X387524Y76847D03*
X374442Y406857D03*
X374542Y401282D03*
X368907Y404308D03*
X376654Y754748D03*
X382892Y767710D03*
X386790Y774338D03*
X379335Y1189778D03*
X383276Y1184136D03*
X386816Y1179841D03*
X376472Y1194999D03*
X373674Y1199967D03*
X371523Y1204725D03*
X366169Y1329686D03*
Y1340201D03*
Y1360043D03*
Y1350706D03*
X373564Y1352548D03*
X366169Y1367771D03*
Y1376210D03*
X374681Y1365620D03*
X367829Y1566108D03*
X366306Y1899864D03*
X374431Y1901397D03*
X374775Y1919243D03*
X379403Y1917261D03*
X369748Y1921795D03*
X402512Y17108D03*
Y67108D03*
Y117108D03*
Y167108D03*
Y217108D03*
Y267108D03*
Y317108D03*
Y367108D03*
Y417108D03*
Y467108D03*
Y517108D03*
Y567108D03*
Y617108D03*
Y667108D03*
Y717108D03*
Y767108D03*
Y817108D03*
Y867108D03*
Y917108D03*
Y967108D03*
Y1017108D03*
Y1067108D03*
Y1117108D03*
Y1167108D03*
Y1217108D03*
Y1267108D03*
Y1317108D03*
Y1367108D03*
Y1417108D03*
Y1467108D03*
Y1517108D03*
Y1567108D03*
Y1617108D03*
Y1667108D03*
Y1717108D03*
Y1767108D03*
Y1817108D03*
Y1867108D03*
Y1917108D03*
Y1967108D03*
Y2017108D03*
Y2067108D03*
G54D30*
X173385Y32520D03*
Y21890D03*
X183385Y32520D03*
Y21890D03*
X193385Y32520D03*
Y21890D03*
X173385Y196890D03*
X183385D03*
X193385D03*
X173385Y207520D03*
X183385D03*
X193385D03*
X173385Y371890D03*
X183385D03*
X193385D03*
X173385Y382520D03*
X183385D03*
X193385D03*
X173386Y557520D03*
Y546890D03*
X183386Y557520D03*
Y546890D03*
X193386Y557520D03*
Y546890D03*
X173386Y732520D03*
Y721890D03*
X183386Y732520D03*
Y721890D03*
X193386Y732520D03*
Y721890D03*
X173385Y896890D03*
X183385D03*
X193385D03*
X173385Y907520D03*
X183385D03*
X193385D03*
X173385Y1071890D03*
X183385D03*
X193385D03*
X173385Y1082520D03*
X183385D03*
X193385D03*
X173385Y1257520D03*
Y1246890D03*
X183385Y1257520D03*
Y1246890D03*
X193385Y1257520D03*
Y1246890D03*
X173385Y1432520D03*
Y1421890D03*
X183385Y1432520D03*
Y1421890D03*
X193385Y1432520D03*
Y1421890D03*
X173385Y1596890D03*
X183385D03*
X193385D03*
X173385Y1607520D03*
X183385D03*
X193385D03*
X173385Y1771890D03*
X183385D03*
X193385D03*
X173385Y1782520D03*
X183385D03*
X193385D03*
X173385Y1957520D03*
Y1946890D03*
X183385Y1957520D03*
Y1946890D03*
X193385Y1957520D03*
Y1946890D03*
X203385Y32520D03*
Y21890D03*
X213385Y32520D03*
Y21890D03*
X203385Y196890D03*
X213385D03*
X203385Y207520D03*
X213385D03*
X203385Y371890D03*
X213385D03*
X203385Y382520D03*
X213385D03*
X203386Y557520D03*
Y546890D03*
X213386Y557520D03*
Y546890D03*
X203386Y732520D03*
Y721890D03*
X213386Y732520D03*
Y721890D03*
X203385Y896890D03*
X213385D03*
X203385Y907520D03*
X213385D03*
X203385Y1071890D03*
X213385D03*
X203385Y1082520D03*
X213385D03*
X203385Y1257520D03*
Y1246890D03*
X213385Y1257520D03*
Y1246890D03*
X203385Y1432520D03*
Y1421890D03*
X213385Y1432520D03*
Y1421890D03*
X203385Y1596890D03*
X213385D03*
X203385Y1607520D03*
X213385D03*
X203385Y1771890D03*
X213385D03*
X203385Y1782520D03*
X213385D03*
X203385Y1957520D03*
Y1946890D03*
X213385Y1957520D03*
Y1946890D03*
X223385Y32520D03*
Y21890D03*
X233385Y32520D03*
Y21890D03*
X243385Y32520D03*
Y21890D03*
X223385Y196890D03*
X233385D03*
X243385D03*
X223385Y207520D03*
X233385D03*
X243385D03*
X223385Y371890D03*
X233385D03*
X243385D03*
X223385Y382520D03*
X233385D03*
X243385D03*
X223386Y557520D03*
Y546890D03*
X233386Y557520D03*
Y546890D03*
X243386Y557520D03*
Y546890D03*
X223386Y732520D03*
Y721890D03*
X233386Y732520D03*
Y721890D03*
X243386Y732520D03*
Y721890D03*
X223385Y896890D03*
X233385D03*
X243385D03*
X223385Y907520D03*
X233385D03*
X243385D03*
X223385Y1071890D03*
X233385D03*
X243385D03*
X223385Y1082520D03*
X233385D03*
X243385D03*
X223385Y1257520D03*
Y1246890D03*
X233385Y1257520D03*
Y1246890D03*
X243385Y1257520D03*
Y1246890D03*
X223385Y1432520D03*
Y1421890D03*
X233385Y1432520D03*
Y1421890D03*
X243385Y1432520D03*
Y1421890D03*
X223385Y1596890D03*
X233385D03*
X243385D03*
X223385Y1607520D03*
X233385D03*
X243385D03*
X223385Y1771890D03*
X233385D03*
X243385D03*
X223385Y1782520D03*
X233385D03*
X243385D03*
X223385Y1957520D03*
Y1946890D03*
X233385Y1957520D03*
Y1946890D03*
X243385Y1957520D03*
Y1946890D03*
X337165Y24705D03*
Y34705D03*
Y199705D03*
Y209705D03*
Y374705D03*
Y384705D03*
X337166Y549705D03*
Y559705D03*
Y724705D03*
Y734705D03*
X337165Y899705D03*
Y909705D03*
Y1074705D03*
Y1084705D03*
Y1249705D03*
Y1259705D03*
Y1424705D03*
Y1434705D03*
Y1599705D03*
Y1609705D03*
Y1774705D03*
Y1784705D03*
Y1949705D03*
Y1959705D03*
X342165Y19705D03*
Y29705D03*
X347165Y24705D03*
X352165Y19705D03*
Y29705D03*
X357165Y24705D03*
X362165Y19705D03*
Y29705D03*
X347165Y34705D03*
X357165D03*
X342165Y194705D03*
X347165Y199705D03*
X352165Y194705D03*
X357165Y199705D03*
X362165Y194705D03*
X342165Y204705D03*
X347165Y209705D03*
X352165Y204705D03*
X357165Y209705D03*
X362165Y204705D03*
X342165Y369705D03*
X352165D03*
X362165D03*
X342165Y379705D03*
X347165Y374705D03*
Y384705D03*
X352165Y379705D03*
X357165Y374705D03*
Y384705D03*
X362165Y379705D03*
X342166Y544705D03*
Y554705D03*
X347166Y549705D03*
Y559705D03*
X352166Y544705D03*
Y554705D03*
X357166Y549705D03*
Y559705D03*
X362166Y544705D03*
Y554705D03*
X342166Y719705D03*
Y729705D03*
X347166Y724705D03*
X352166Y719705D03*
Y729705D03*
X357166Y724705D03*
X362166Y719705D03*
Y729705D03*
X347166Y734705D03*
X357166D03*
X342165Y894705D03*
X347165Y899705D03*
X352165Y894705D03*
X357165Y899705D03*
X362165Y894705D03*
X342165Y904705D03*
X347165Y909705D03*
X352165Y904705D03*
X357165Y909705D03*
X362165Y904705D03*
X342165Y1069705D03*
X352165D03*
X362165D03*
X342165Y1079705D03*
X347165Y1074705D03*
Y1084705D03*
X352165Y1079705D03*
X357165Y1074705D03*
Y1084705D03*
X362165Y1079705D03*
X342165Y1244705D03*
Y1254705D03*
X347165Y1249705D03*
Y1259705D03*
X352165Y1244705D03*
Y1254705D03*
X357165Y1249705D03*
Y1259705D03*
X362165Y1244705D03*
Y1254705D03*
X342165Y1419705D03*
Y1429705D03*
X347165Y1424705D03*
Y1434705D03*
X352165Y1419705D03*
Y1429705D03*
X357165Y1424705D03*
Y1434705D03*
X362165Y1419705D03*
Y1429705D03*
X342165Y1594705D03*
X347165Y1599705D03*
X352165Y1594705D03*
X357165Y1599705D03*
X362165Y1594705D03*
X342165Y1604705D03*
X347165Y1609705D03*
X352165Y1604705D03*
X357165Y1609705D03*
X362165Y1604705D03*
X342165Y1769705D03*
X352165D03*
X362165D03*
X342165Y1779705D03*
X347165Y1774705D03*
Y1784705D03*
X352165Y1779705D03*
X357165Y1774705D03*
Y1784705D03*
X362165Y1779705D03*
X342165Y1944705D03*
Y1954705D03*
X347165Y1949705D03*
Y1959705D03*
X352165Y1944705D03*
Y1954705D03*
X357165Y1949705D03*
Y1959705D03*
X362165Y1944705D03*
Y1954705D03*
G54D24*
X65354Y101180D03*
X55511Y105117D03*
X51574Y114960D03*
X55511Y124803D03*
X65354Y128740D03*
Y451180D03*
X55511Y455117D03*
X51574Y464960D03*
X55511Y474803D03*
X65354Y478740D03*
Y801180D03*
X55511Y805117D03*
X51574Y814960D03*
X55511Y824803D03*
X65354Y828740D03*
Y1151180D03*
X55511Y1155117D03*
X51574Y1164960D03*
X55511Y1174803D03*
X65354Y1178740D03*
Y1501180D03*
X55511Y1505117D03*
X51574Y1514960D03*
X55511Y1524803D03*
X65354Y1528740D03*
Y1851180D03*
X55511Y1855117D03*
X51574Y1864960D03*
X55511Y1874803D03*
X65354Y1878740D03*
X75197Y105117D03*
Y124803D03*
X79134Y114960D03*
Y464960D03*
X75197Y455117D03*
Y474803D03*
Y805117D03*
Y824803D03*
X79134Y814960D03*
Y1164960D03*
X75197Y1155117D03*
Y1174803D03*
Y1505117D03*
Y1524803D03*
X79134Y1514960D03*
Y1864960D03*
X75197Y1855117D03*
Y1874803D03*
X307086Y113385D03*
X297243Y117322D03*
X293306Y127165D03*
X297243Y137008D03*
X307086Y140945D03*
Y463385D03*
X297243Y467322D03*
X293306Y477165D03*
X297243Y487008D03*
X307086Y490945D03*
Y813385D03*
X297243Y817322D03*
X293306Y827165D03*
X297243Y837008D03*
X307086Y840945D03*
Y1329724D03*
X297243Y1333661D03*
X293306Y1343504D03*
X297243Y1353347D03*
X307086Y1357284D03*
Y1679724D03*
X297243Y1683661D03*
X293306Y1693504D03*
X297243Y1703347D03*
X307086Y1707284D03*
X307087Y2029723D03*
X297244Y2033660D03*
X293307Y2043503D03*
X297244Y2053346D03*
X307087Y2057283D03*
X320866Y127165D03*
X316929Y117322D03*
Y137008D03*
Y467322D03*
Y487008D03*
X320866Y477165D03*
Y827165D03*
X316929Y817322D03*
Y837008D03*
Y1333661D03*
Y1353347D03*
X320866Y1343504D03*
Y1693504D03*
X316929Y1683661D03*
Y1703347D03*
X316930Y2033660D03*
Y2053346D03*
X320867Y2043503D03*
G54D12*
X22756Y113818D03*
Y125629D03*
X22480Y316838D03*
Y340460D03*
X22756Y1866819D03*
Y1878630D03*
Y1948818D03*
Y1960629D03*
Y2023818D03*
Y2035629D03*
G54D20*
X30473Y102007D03*
Y137440D03*
X30197Y305027D03*
Y352271D03*
X30473Y1855008D03*
Y1890441D03*
Y1937007D03*
Y1972440D03*
Y2012007D03*
Y2047440D03*
G54D27*
X119920Y18071D03*
Y28071D03*
Y38071D03*
Y48071D03*
Y58071D03*
Y68071D03*
Y78071D03*
Y88071D03*
Y98071D03*
Y108071D03*
Y118071D03*
Y128071D03*
Y138071D03*
Y148071D03*
Y158071D03*
Y168071D03*
Y178071D03*
Y188071D03*
Y198071D03*
Y208071D03*
Y366102D03*
Y376102D03*
Y386102D03*
Y396102D03*
Y406102D03*
Y416102D03*
Y426102D03*
Y436102D03*
Y446102D03*
Y456102D03*
Y466102D03*
Y476102D03*
Y486102D03*
Y496102D03*
Y506102D03*
Y516102D03*
Y526102D03*
Y536102D03*
Y546102D03*
Y556102D03*
Y714134D03*
Y724134D03*
Y734134D03*
Y744134D03*
Y754134D03*
Y764134D03*
Y774134D03*
Y784134D03*
Y794134D03*
Y804134D03*
Y814134D03*
Y824134D03*
Y834134D03*
Y844134D03*
Y854134D03*
Y864134D03*
Y874134D03*
Y884134D03*
Y894134D03*
Y904134D03*
Y1062165D03*
Y1072165D03*
Y1082165D03*
Y1092165D03*
Y1102165D03*
Y1112165D03*
Y1122165D03*
Y1132165D03*
Y1142165D03*
Y1152165D03*
Y1162165D03*
Y1172165D03*
Y1182165D03*
Y1192165D03*
Y1202165D03*
Y1212165D03*
Y1222165D03*
Y1232165D03*
Y1242165D03*
Y1252165D03*
Y1410197D03*
Y1420197D03*
Y1430197D03*
Y1440197D03*
Y1450197D03*
Y1460197D03*
Y1470197D03*
Y1480197D03*
Y1490197D03*
Y1500197D03*
Y1510197D03*
Y1520197D03*
Y1530197D03*
Y1540197D03*
Y1550197D03*
Y1560197D03*
Y1570197D03*
Y1580197D03*
Y1590197D03*
Y1600197D03*
Y1758228D03*
Y1768228D03*
Y1778228D03*
Y1788228D03*
Y1798228D03*
Y1808228D03*
Y1818228D03*
Y1828228D03*
Y1838228D03*
Y1848228D03*
Y1858228D03*
Y1868228D03*
Y1878228D03*
Y1888228D03*
Y1898228D03*
Y1908228D03*
Y1918228D03*
Y1928228D03*
Y1938228D03*
Y1948228D03*
X139920Y28071D03*
Y18071D03*
Y58071D03*
Y48071D03*
Y38071D03*
Y78071D03*
Y68071D03*
Y98071D03*
Y88071D03*
Y128071D03*
Y118071D03*
Y108071D03*
Y148071D03*
Y138071D03*
Y178071D03*
Y168071D03*
Y158071D03*
Y198071D03*
Y188071D03*
Y208071D03*
Y366102D03*
Y396102D03*
Y386102D03*
Y376102D03*
Y416102D03*
Y406102D03*
Y436102D03*
Y426102D03*
Y466102D03*
Y456102D03*
Y446102D03*
Y486102D03*
Y476102D03*
Y516102D03*
Y506102D03*
Y496102D03*
Y536102D03*
Y526102D03*
Y556102D03*
Y546102D03*
Y734134D03*
Y724134D03*
Y714134D03*
Y754134D03*
Y744134D03*
Y774134D03*
Y764134D03*
Y804134D03*
Y794134D03*
Y784134D03*
Y824134D03*
Y814134D03*
Y854134D03*
Y844134D03*
Y834134D03*
Y874134D03*
Y864134D03*
Y904134D03*
Y894134D03*
Y884134D03*
Y1072165D03*
Y1062165D03*
Y1092165D03*
Y1082165D03*
Y1122165D03*
Y1112165D03*
Y1102165D03*
Y1142165D03*
Y1132165D03*
Y1162165D03*
Y1152165D03*
Y1192165D03*
Y1182165D03*
Y1172165D03*
Y1212165D03*
Y1202165D03*
Y1242165D03*
Y1232165D03*
Y1222165D03*
Y1252165D03*
Y1410197D03*
Y1430197D03*
Y1420197D03*
Y1460197D03*
Y1450197D03*
Y1440197D03*
Y1480197D03*
Y1470197D03*
Y1500197D03*
Y1490197D03*
Y1530197D03*
Y1520197D03*
Y1510197D03*
Y1550197D03*
Y1540197D03*
Y1580197D03*
Y1570197D03*
Y1560197D03*
Y1600197D03*
Y1590197D03*
Y1768228D03*
Y1758228D03*
Y1798228D03*
Y1788228D03*
Y1778228D03*
Y1818228D03*
Y1808228D03*
Y1838228D03*
Y1828228D03*
Y1868228D03*
Y1858228D03*
Y1848228D03*
Y1888228D03*
Y1878228D03*
Y1918228D03*
Y1908228D03*
Y1898228D03*
Y1938228D03*
Y1928228D03*
Y1948228D03*
G54D14*
X14073Y512197D03*
Y522000D03*
Y552000D03*
Y561803D03*
Y1580004D03*
Y1570201D03*
Y1610004D03*
Y1619807D03*
X65254Y519500D03*
Y529500D03*
Y539500D03*
X55254Y524500D03*
Y534500D03*
X65254Y549500D03*
X55254Y544500D03*
Y554500D03*
X65254Y1577504D03*
Y1587504D03*
Y1597504D03*
X55254Y1582504D03*
Y1592504D03*
Y1602504D03*
X65254Y1607504D03*
X55254Y1612504D03*
X189762Y73105D03*
X190289Y152050D03*
X190357Y247568D03*
X190817Y331786D03*
X189761Y421732D03*
X190553Y506517D03*
X192888Y598130D03*
X190816Y681645D03*
X191846Y774526D03*
X191606Y856244D03*
X196311Y947202D03*
X195516Y1032544D03*
X191250Y1122856D03*
X191342Y1206233D03*
X191846Y1299104D03*
X190552Y1380966D03*
X189463Y1474162D03*
X191079Y1557277D03*
X192143Y1648177D03*
X191607Y1731351D03*
X191530Y1823227D03*
X190289Y1900420D03*
X192125Y1998730D03*
X191530Y2043388D03*
G54D21*
X45411Y505996D03*
Y568004D03*
Y1564000D03*
Y1626008D03*
G54D16*
X15547Y707364D03*
Y723112D03*
Y730986D03*
X25389Y723112D03*
Y730986D03*
X7673Y719175D03*
Y727049D03*
X15547Y738860D03*
Y746734D03*
Y754608D03*
X25389Y738860D03*
Y746734D03*
Y754608D03*
X7673Y734923D03*
Y742797D03*
Y750671D03*
Y758545D03*
X15547Y762483D03*
Y770357D03*
Y778231D03*
X25389Y762483D03*
Y770357D03*
Y778231D03*
X7673Y766419D03*
Y774293D03*
Y782167D03*
X15547Y786105D03*
Y793979D03*
Y801853D03*
X25389Y786105D03*
Y793979D03*
Y801853D03*
X7673Y790041D03*
Y797915D03*
Y805790D03*
X15547Y809727D03*
Y817601D03*
Y825475D03*
X25389Y809727D03*
Y817601D03*
Y825475D03*
X7673Y813664D03*
Y821538D03*
Y829412D03*
X15547Y833349D03*
Y841223D03*
Y849097D03*
X25389Y833349D03*
Y841223D03*
Y849097D03*
X7673Y837286D03*
Y845160D03*
Y853034D03*
X15547Y856971D03*
Y864845D03*
Y872719D03*
X25389Y856971D03*
Y864845D03*
Y872719D03*
X7673Y860908D03*
Y868782D03*
Y876656D03*
X15547Y880593D03*
Y888467D03*
Y896341D03*
X25389Y880593D03*
Y888467D03*
Y896341D03*
X7673Y884530D03*
Y892404D03*
Y900278D03*
X15547Y904215D03*
Y912089D03*
Y919963D03*
X25389Y904215D03*
Y912089D03*
Y919963D03*
X7673Y908152D03*
Y916026D03*
Y923900D03*
X15547Y927837D03*
Y935711D03*
Y943585D03*
Y951459D03*
X25389Y927837D03*
Y935711D03*
Y943585D03*
Y951459D03*
X7673Y931774D03*
Y939648D03*
Y947522D03*
X15547Y959333D03*
Y967207D03*
Y975081D03*
X25389Y959333D03*
Y967207D03*
Y975081D03*
X7673Y955396D03*
Y963270D03*
Y971144D03*
Y979018D03*
Y994766D03*
X15547Y990829D03*
Y998703D03*
X25389Y990829D03*
Y998703D03*
X7673Y1002640D03*
Y1010514D03*
Y1018388D03*
X15547Y1006577D03*
Y1014451D03*
Y1022325D03*
X25389Y1006577D03*
Y1014451D03*
Y1022325D03*
X7673Y1026262D03*
X15547Y1030199D03*
X25389D03*
X15551Y1065629D03*
X25393D03*
X7677Y1061692D03*
Y1069566D03*
X15551Y1073503D03*
Y1081377D03*
Y1089251D03*
X25393Y1073503D03*
Y1081377D03*
Y1089251D03*
X7677Y1077440D03*
Y1085314D03*
Y1093188D03*
X15551Y1097125D03*
Y1104999D03*
Y1112873D03*
Y1120748D03*
X25393Y1097125D03*
Y1104999D03*
Y1112873D03*
Y1120748D03*
X7677Y1101062D03*
Y1108936D03*
Y1116810D03*
X15551Y1128622D03*
Y1136496D03*
Y1144370D03*
X25393Y1128622D03*
Y1136496D03*
Y1144370D03*
X7677Y1124684D03*
Y1132558D03*
Y1140432D03*
X15551Y1152244D03*
Y1160118D03*
Y1167992D03*
X25393Y1152244D03*
Y1160118D03*
Y1167992D03*
X7677Y1148306D03*
Y1156180D03*
Y1164055D03*
X15551Y1175866D03*
Y1183740D03*
Y1191614D03*
X25393Y1175866D03*
Y1183740D03*
Y1191614D03*
X7677Y1171929D03*
Y1179803D03*
Y1187677D03*
X15551Y1199488D03*
Y1207362D03*
Y1215236D03*
X25393Y1199488D03*
Y1207362D03*
Y1215236D03*
X7677Y1195551D03*
Y1203425D03*
Y1211299D03*
X15551Y1223110D03*
Y1230984D03*
Y1238858D03*
X25393Y1223110D03*
Y1230984D03*
Y1238858D03*
X7677Y1219173D03*
Y1227047D03*
Y1234921D03*
X15551Y1246732D03*
Y1254606D03*
Y1262480D03*
X25393Y1246732D03*
Y1254606D03*
Y1262480D03*
X7677Y1242795D03*
Y1250669D03*
Y1258543D03*
X15551Y1270354D03*
Y1278228D03*
Y1286102D03*
X25393Y1270354D03*
Y1278228D03*
Y1286102D03*
X7677Y1266417D03*
Y1274291D03*
Y1282165D03*
X15551Y1293976D03*
Y1301850D03*
Y1309724D03*
X25393Y1293976D03*
Y1301850D03*
Y1309724D03*
X7677Y1290039D03*
Y1297913D03*
Y1305787D03*
Y1313661D03*
X15551Y1317598D03*
Y1325472D03*
Y1333346D03*
X25393Y1317598D03*
Y1325472D03*
Y1333346D03*
X7677Y1321535D03*
Y1329409D03*
Y1337283D03*
Y1353031D03*
Y1360905D03*
X15551Y1349094D03*
Y1356968D03*
X25393Y1349094D03*
Y1356968D03*
X7677Y1368779D03*
Y1376653D03*
Y1384527D03*
X15551Y1364842D03*
Y1372716D03*
Y1380590D03*
X25393Y1364842D03*
Y1372716D03*
Y1380590D03*
X15551Y1388464D03*
X25393D03*
X33263Y727049D03*
Y734923D03*
Y742797D03*
Y750671D03*
Y758545D03*
Y766419D03*
Y774293D03*
Y782167D03*
Y790041D03*
Y797915D03*
Y805790D03*
Y813664D03*
Y821538D03*
Y829412D03*
Y837286D03*
Y845160D03*
Y853034D03*
Y860908D03*
Y868782D03*
Y876656D03*
Y884530D03*
Y892404D03*
Y900278D03*
Y908152D03*
Y916026D03*
Y923900D03*
Y931774D03*
Y939648D03*
Y947522D03*
Y955396D03*
Y963270D03*
Y971144D03*
Y979018D03*
Y994766D03*
Y1002640D03*
Y1010514D03*
Y1018388D03*
Y1026262D03*
X33267Y1061692D03*
Y1069566D03*
Y1077440D03*
Y1085314D03*
Y1093188D03*
Y1101062D03*
Y1108936D03*
Y1116810D03*
Y1124684D03*
Y1132558D03*
Y1140432D03*
Y1148306D03*
Y1156180D03*
Y1164055D03*
Y1171929D03*
Y1179803D03*
Y1187677D03*
Y1195551D03*
Y1203425D03*
Y1211299D03*
Y1219173D03*
Y1227047D03*
Y1234921D03*
Y1242795D03*
Y1250669D03*
Y1258543D03*
Y1266417D03*
Y1274291D03*
Y1282165D03*
Y1290039D03*
Y1297913D03*
Y1305787D03*
Y1313661D03*
Y1321535D03*
Y1329409D03*
Y1337283D03*
Y1353031D03*
Y1360905D03*
Y1368779D03*
Y1376653D03*
Y1384527D03*
G54D19*
X23402Y1668874D03*
Y1685410D03*
Y1701945D03*
Y1718480D03*
Y1735016D03*
Y1751551D03*
Y1768087D03*
Y1784622D03*
Y1817693D03*
Y1801158D03*
X45056Y1668874D03*
Y1718480D03*
Y1768087D03*
Y1817693D03*
G54D23*
X64979Y35500D03*
Y45500D03*
Y55500D03*
X54979Y40500D03*
Y50500D03*
X64979Y65500D03*
X54979Y60500D03*
Y70500D03*
X64979Y171500D03*
X54979Y176500D03*
X64979Y181500D03*
Y191500D03*
Y201500D03*
X54979Y186500D03*
Y196500D03*
Y206500D03*
X64979Y244500D03*
X54979Y249500D03*
X64979Y254500D03*
Y264500D03*
Y274500D03*
X54979Y259500D03*
Y269500D03*
Y279500D03*
X64979Y380500D03*
Y390500D03*
X54979Y385500D03*
Y395500D03*
X64979Y400500D03*
Y410500D03*
X54979Y405500D03*
Y415500D03*
G54D13*
X22480Y328649D03*
G54D34*
X307086Y1883071D03*
G54D18*
X20468Y696341D03*
Y984333D03*
X20472Y1054606D03*
Y1342598D03*
G54D10*
X29979Y30500D03*
Y75500D03*
Y166500D03*
Y211500D03*
Y239500D03*
Y284500D03*
Y375500D03*
Y420500D03*
G54D33*
X307086Y308267D03*
G54D15*
X30254Y514500D03*
Y559500D03*
Y1572504D03*
Y1617504D03*
G54D29*
X163385Y27205D03*
Y202205D03*
Y377205D03*
X163386Y552205D03*
Y727205D03*
X163385Y902205D03*
Y1077205D03*
Y1252205D03*
Y1427205D03*
Y1602205D03*
Y1777205D03*
Y1952205D03*
X373385Y32520D03*
Y207520D03*
Y382520D03*
X373386Y557520D03*
Y732520D03*
X373385Y907520D03*
Y1082520D03*
Y1257520D03*
Y1432520D03*
Y1607520D03*
Y1782520D03*
Y1957520D03*
G54D35*
X359842Y78780D03*
Y253780D03*
Y428779D03*
Y603779D03*
Y778780D03*
Y953780D03*
Y1128779D03*
Y1303780D03*
Y1478780D03*
Y1653780D03*
Y1828779D03*
Y2003780D03*
G54D17*
X25389Y707364D03*
X7673Y703427D03*
X15547Y715238D03*
X25389D03*
X7673Y711301D03*
X33263Y703427D03*
Y711301D03*
Y719175D03*
G54D32*
X253385Y21890D03*
Y32520D03*
X263385Y21890D03*
Y32520D03*
X253385Y196890D03*
X263385D03*
X253385Y207520D03*
X263385D03*
X253385Y371890D03*
X263385D03*
X253385Y382520D03*
X263385D03*
X253386Y546890D03*
Y557520D03*
X263386Y546890D03*
Y557520D03*
X253386Y721890D03*
Y732520D03*
X263386Y721890D03*
Y732520D03*
X253385Y896890D03*
X263385D03*
X253385Y907520D03*
X263385D03*
X253385Y1071890D03*
X263385D03*
X253385Y1082520D03*
X263385D03*
X253385Y1246890D03*
Y1257520D03*
X263385Y1246890D03*
Y1257520D03*
X253385Y1421890D03*
Y1432520D03*
X263385Y1421890D03*
Y1432520D03*
X253385Y1596890D03*
X263385D03*
X253385Y1607520D03*
X263385D03*
X253385Y1771890D03*
X263385D03*
X253385Y1782520D03*
X263385D03*
X253385Y1946890D03*
Y1957520D03*
X263385Y1946890D03*
Y1957520D03*
X273385Y21890D03*
Y32520D03*
X283385Y21890D03*
Y32520D03*
X273385Y196890D03*
X283385D03*
X273385Y207520D03*
X283385D03*
X273385Y371890D03*
X283385D03*
X273385Y382520D03*
X283385D03*
X273386Y546890D03*
Y557520D03*
X283386Y546890D03*
Y557520D03*
X273386Y721890D03*
Y732520D03*
X283386Y721890D03*
Y732520D03*
X273385Y896890D03*
X283385D03*
X273385Y907520D03*
X283385D03*
X273385Y1071890D03*
X283385D03*
X273385Y1082520D03*
X283385D03*
X273385Y1246890D03*
Y1257520D03*
X283385Y1246890D03*
Y1257520D03*
X273385Y1421890D03*
Y1432520D03*
X283385Y1421890D03*
Y1432520D03*
X273385Y1596890D03*
X283385D03*
X273385Y1607520D03*
X283385D03*
X273385Y1771890D03*
X283385D03*
X273385Y1782520D03*
X283385D03*
X273385Y1946890D03*
Y1957520D03*
X283385Y1946890D03*
Y1957520D03*
X293385Y21890D03*
Y32520D03*
X303385Y21890D03*
Y32520D03*
X313385D03*
Y21890D03*
X293385Y196890D03*
X303385D03*
X313385D03*
X293385Y207520D03*
X303385D03*
X313385D03*
X293385Y371890D03*
X303385D03*
X313385D03*
X293385Y382520D03*
X303385D03*
X313385D03*
X293386Y546890D03*
Y557520D03*
X303386Y546890D03*
Y557520D03*
X313386D03*
Y546890D03*
X293386Y721890D03*
Y732520D03*
X303386Y721890D03*
Y732520D03*
X313386D03*
Y721890D03*
X293385Y896890D03*
X303385D03*
X313385D03*
X293385Y907520D03*
X303385D03*
X313385D03*
X293385Y1071890D03*
X303385D03*
X313385D03*
X293385Y1082520D03*
X303385D03*
X313385D03*
X293385Y1246890D03*
Y1257520D03*
X303385Y1246890D03*
Y1257520D03*
X313385D03*
Y1246890D03*
X293385Y1421890D03*
Y1432520D03*
X303385Y1421890D03*
Y1432520D03*
X313385D03*
Y1421890D03*
X293385Y1596890D03*
X303385D03*
X313385D03*
X293385Y1607520D03*
X303385D03*
X313385D03*
X293385Y1771890D03*
X303385D03*
X313385D03*
X293385Y1782520D03*
X303385D03*
X313385D03*
X293385Y1946890D03*
Y1957520D03*
X303385Y1946890D03*
Y1957520D03*
X313385D03*
Y1946890D03*
X323385Y32520D03*
Y21890D03*
Y196890D03*
Y207520D03*
Y371890D03*
Y382520D03*
X323386Y557520D03*
Y546890D03*
Y732520D03*
Y721890D03*
X323385Y896890D03*
Y907520D03*
Y1071890D03*
Y1082520D03*
Y1257520D03*
Y1246890D03*
Y1432520D03*
Y1421890D03*
Y1596890D03*
Y1607520D03*
Y1771890D03*
Y1782520D03*
Y1957520D03*
Y1946890D03*
G54D25*
X65354Y114960D03*
Y464960D03*
Y814960D03*
Y1164960D03*
Y1514960D03*
Y1864960D03*
X307086Y127165D03*
Y477165D03*
Y827165D03*
Y1343504D03*
Y1693504D03*
X307087Y2043503D03*
G54D26*
X59127Y1257647D03*
X58356Y1279812D03*
X58416Y1272383D03*
X161339Y88108D03*
X168975Y265783D03*
X165975D03*
X168975Y296140D03*
Y286803D03*
Y276298D03*
X165975D03*
Y286803D03*
Y296140D03*
X168975Y312307D03*
Y303868D03*
X165975D03*
Y312307D03*
X161517Y436119D03*
X157272Y604773D03*
X160272D03*
X157272Y633416D03*
Y613574D03*
Y624079D03*
X160272D03*
Y613574D03*
Y633416D03*
X157272Y641144D03*
Y649583D03*
X160272D03*
Y641144D03*
X161479Y784141D03*
X163699Y972924D03*
X166699D03*
X163699Y983439D03*
Y993944D03*
X166699D03*
Y983439D03*
X163424Y1011298D03*
Y1003570D03*
Y1019737D03*
X166424D03*
Y1003570D03*
Y1011298D03*
X158749Y1307733D03*
X155749D03*
X158749Y1328753D03*
Y1318248D03*
X155749D03*
Y1328753D03*
X158749Y1354257D03*
Y1338090D03*
Y1345818D03*
X155749D03*
Y1338090D03*
Y1354257D03*
X161492Y1667763D03*
Y1657248D03*
X158492D03*
Y1667763D03*
X161492Y1695333D03*
Y1687605D03*
Y1678268D03*
X158492D03*
Y1687605D03*
Y1695333D03*
X161492Y1703772D03*
X158492D03*
X161844Y1828225D03*
X217732Y153964D03*
Y170131D03*
Y161692D03*
Y164692D03*
Y173131D03*
Y156964D03*
X219214Y1287272D03*
Y1301975D03*
X219349Y1308924D03*
X219214Y1294491D03*
X219178Y1324285D03*
Y1332321D03*
Y1316842D03*
Y1339840D03*
X238741Y153964D03*
X227700D03*
X238741Y170131D03*
Y161692D03*
X227700Y170131D03*
Y161692D03*
Y164692D03*
Y173131D03*
X238741Y164692D03*
Y173131D03*
X227700Y156964D03*
X238741D03*
X239746Y407393D03*
Y396878D03*
Y417898D03*
Y399878D03*
Y410393D03*
Y420898D03*
X234012Y754782D03*
X237012D03*
X234012Y762510D03*
Y770949D03*
X237012D03*
Y762510D03*
X241396Y862887D03*
Y855159D03*
Y871326D03*
X238396D03*
Y855159D03*
Y862887D03*
X235709Y1124900D03*
Y1135415D03*
X232709D03*
Y1124900D03*
X242677Y1135415D03*
Y1124900D03*
X235709Y1145920D03*
X232709D03*
X242677D03*
X226642Y1287272D03*
X222214D03*
X229642D03*
X226642Y1301975D03*
X235465D03*
X226777Y1308924D03*
X235600D03*
X242961Y1301975D03*
X243096Y1308924D03*
X226642Y1294491D03*
X235465D03*
X242961D03*
X222214D03*
X222349Y1308924D03*
X222214Y1301975D03*
X238465Y1294491D03*
X229642D03*
X238600Y1308924D03*
X229777D03*
X238465Y1301975D03*
X229642D03*
X226606Y1324285D03*
X235429D03*
X226606Y1332321D03*
X235429D03*
X242925Y1324285D03*
Y1332321D03*
X226606Y1316842D03*
X235429D03*
X242925D03*
X222178D03*
Y1332321D03*
Y1324285D03*
X238429Y1316842D03*
X229606D03*
X238429Y1332321D03*
X229606D03*
X238429Y1324285D03*
X229606D03*
X226606Y1339840D03*
X235429D03*
X242925D03*
X222178D03*
X238429D03*
X229606D03*
X226573Y2031480D03*
X236541D03*
X226573Y2020965D03*
X236541D03*
X242582D03*
Y2031480D03*
X231541Y2020965D03*
X221573D03*
X231541Y2031480D03*
X221573D03*
X226573Y2059050D03*
X236541Y2051322D03*
Y2059050D03*
X226573Y2041985D03*
Y2051322D03*
X236541Y2041985D03*
X242582Y2059050D03*
Y2051322D03*
Y2041985D03*
X231541D03*
X221573Y2051322D03*
Y2041985D03*
X231541Y2059050D03*
Y2051322D03*
X221573Y2059050D03*
X236541Y2067489D03*
X226573D03*
X242582D03*
X221573D03*
X231541D03*
X256566Y54944D03*
X264104D03*
X256566Y45572D03*
X264104D03*
Y48572D03*
X256566D03*
Y65449D03*
X264104D03*
Y57944D03*
X256566D03*
X264104Y68449D03*
X256566D03*
X256861Y153964D03*
X248083D03*
X256861Y170131D03*
Y161692D03*
X248083Y170131D03*
Y161692D03*
Y164692D03*
Y173131D03*
X256861Y164692D03*
Y173131D03*
X248083Y156964D03*
X256861D03*
X264596Y221664D03*
X252818D03*
X255818D03*
X261596D03*
X264596Y242684D03*
Y232179D03*
X252818Y242684D03*
Y232179D03*
X255818D03*
Y242684D03*
X261596Y232179D03*
Y242684D03*
X264596Y268188D03*
Y259749D03*
Y252021D03*
X252818Y268188D03*
Y252021D03*
Y259749D03*
X255818D03*
Y252021D03*
Y268188D03*
X261596Y252021D03*
Y259749D03*
Y268188D03*
X266040Y407146D03*
Y396631D03*
Y417651D03*
X257572Y396630D03*
Y407145D03*
X248714Y407536D03*
Y397021D03*
X257572Y417650D03*
X248714Y418041D03*
Y400021D03*
Y410536D03*
X257572Y410145D03*
Y399630D03*
X266040Y399631D03*
Y410146D03*
X248714Y421041D03*
X257572Y420650D03*
X266040Y420651D03*
X267166Y581440D03*
Y572639D03*
X264166D03*
Y581440D03*
X267166Y609010D03*
Y601282D03*
Y591945D03*
X264166D03*
Y601282D03*
Y609010D03*
X267166Y617449D03*
X264166D03*
X243980Y754782D03*
X255021D03*
X258021D03*
X246980D03*
X243980Y762510D03*
Y770949D03*
X255021Y762510D03*
Y770949D03*
X258021D03*
Y762510D03*
X246980Y770949D03*
Y762510D03*
X253174Y855159D03*
Y862887D03*
Y871326D03*
X250174D03*
Y862887D03*
Y855159D03*
X265766Y949344D03*
X262766D03*
X265766Y967106D03*
Y959859D03*
X265621Y974386D03*
X262621D03*
X262766Y959859D03*
Y967106D03*
X265621Y990553D03*
Y982114D03*
X262621D03*
Y990553D03*
X263473Y1124613D03*
Y1135128D03*
X245677Y1124900D03*
Y1135415D03*
X254433Y1135271D03*
Y1124756D03*
X251433D03*
Y1135271D03*
X260473Y1135128D03*
Y1124613D03*
X263473Y1145633D03*
X245677Y1145920D03*
X254433Y1145776D03*
X251433D03*
X260473Y1145633D03*
X259581Y1272430D03*
Y1282945D03*
X256581D03*
Y1272430D03*
X267622D03*
Y1282945D03*
X245961Y1294491D03*
X246096Y1308924D03*
X245961Y1301975D03*
X259581Y1293450D03*
Y1302787D03*
Y1310515D03*
X256581D03*
Y1302787D03*
Y1293450D03*
X267622Y1310515D03*
Y1302787D03*
Y1293450D03*
X245925Y1316842D03*
Y1332321D03*
Y1324285D03*
X259581Y1318954D03*
X256581D03*
X267622D03*
X245925Y1339840D03*
X260939Y1548010D03*
Y1534139D03*
Y1541055D03*
X263939D03*
Y1534139D03*
Y1548010D03*
X258564Y1621823D03*
X261564D03*
X258564Y1642843D03*
Y1632338D03*
X261564D03*
Y1642843D03*
X258564Y1668347D03*
Y1659908D03*
Y1652180D03*
X261564D03*
Y1659908D03*
Y1668347D03*
X262759Y1697613D03*
Y1676593D03*
Y1687108D03*
X251718Y1697613D03*
Y1687108D03*
Y1676593D03*
X254718D03*
Y1687108D03*
X265759D03*
Y1676593D03*
X254718Y1697613D03*
X265759D03*
X262498Y1722140D03*
X262759Y1714678D03*
Y1706950D03*
X251457Y1722140D03*
X251718Y1714678D03*
Y1706950D03*
X265759D03*
X254718D03*
Y1714678D03*
X265759D03*
X265498Y1722140D03*
X254457D03*
X261639Y1819074D03*
Y1812119D03*
Y1805203D03*
X253468Y1819074D03*
Y1812119D03*
Y1805203D03*
X267396Y1812122D03*
Y1805206D03*
Y1819077D03*
X250468Y1805203D03*
Y1812119D03*
Y1819074D03*
X258639Y1805203D03*
Y1812119D03*
Y1819074D03*
X261459Y1826219D03*
X253288D03*
X261459Y1840090D03*
Y1833135D03*
X253288D03*
Y1840090D03*
X250288D03*
Y1833135D03*
X267037Y1840093D03*
Y1833138D03*
X258459Y1833135D03*
Y1840090D03*
X267037Y1826222D03*
X250288Y1826219D03*
X258459D03*
X247582Y2031480D03*
Y2020965D03*
X260337D03*
Y2031480D03*
X267115Y2020965D03*
Y2031480D03*
X255337D03*
Y2020965D03*
X247582Y2041985D03*
Y2051322D03*
Y2059050D03*
X260337Y2051322D03*
Y2059050D03*
Y2041985D03*
X267115D03*
Y2059050D03*
Y2051322D03*
X255337Y2041985D03*
Y2059050D03*
Y2051322D03*
X260337Y2067489D03*
X247582D03*
X267115D03*
X255337D03*
X288102Y54944D03*
Y45572D03*
X271572Y54944D03*
X279754D03*
X271572Y45572D03*
X279754D03*
Y48572D03*
X271572D03*
X288102D03*
Y65449D03*
X271572D03*
X279754D03*
Y57944D03*
X271572D03*
X288102D03*
X279754Y68449D03*
X271572D03*
X288102D03*
X274531Y407289D03*
Y396774D03*
Y417794D03*
Y399774D03*
Y410289D03*
Y420794D03*
X289569Y532762D03*
Y516595D03*
Y524323D03*
X278944Y581440D03*
Y572639D03*
X275944D03*
Y581440D03*
X278944Y601282D03*
Y609010D03*
Y591945D03*
X275944D03*
Y609010D03*
Y601282D03*
X278944Y617449D03*
X275944D03*
X277544Y949344D03*
X274544D03*
X277544Y967106D03*
Y959859D03*
X277399Y974386D03*
X274399D03*
X274544Y959859D03*
Y967106D03*
X277399Y990553D03*
Y982114D03*
X274399D03*
Y990553D03*
X272821Y1124471D03*
Y1134986D03*
X269821D03*
Y1124471D03*
X272821Y1145491D03*
X269821D03*
X284182Y1184455D03*
Y1192183D03*
X287182D03*
Y1184455D03*
X284182Y1200622D03*
X287182D03*
X270622Y1282945D03*
Y1272430D03*
Y1293450D03*
Y1302787D03*
Y1310515D03*
Y1318954D03*
X275400Y1548190D03*
X268534Y1548010D03*
X282995Y1548190D03*
X275400Y1534319D03*
Y1541235D03*
X268534Y1534139D03*
Y1541055D03*
X282995Y1534319D03*
Y1541235D03*
X285995D03*
Y1534319D03*
X271534Y1541055D03*
Y1534139D03*
X278400Y1541235D03*
Y1534319D03*
X285995Y1548190D03*
X271534Y1548010D03*
X278400Y1548190D03*
X270342Y1621823D03*
X273342D03*
X270342Y1642843D03*
Y1632338D03*
X273342D03*
Y1642843D03*
X270342Y1668347D03*
Y1652180D03*
Y1659908D03*
X273342D03*
Y1652180D03*
Y1668347D03*
X270396Y1819077D03*
Y1805206D03*
Y1812122D03*
X270037Y1826222D03*
Y1833138D03*
Y1840093D03*
X272115Y2031480D03*
Y2020965D03*
Y2051322D03*
Y2059050D03*
Y2041985D03*
Y2067489D03*
X300537Y516309D03*
X307966Y516419D03*
Y524147D03*
X300537Y524037D03*
Y532476D03*
X307966Y532586D03*
X292569Y524323D03*
Y516595D03*
Y532762D03*
X304966Y532586D03*
X297537Y532476D03*
Y524037D03*
X304966Y524147D03*
Y516419D03*
X297537Y516309D03*
X313791Y532871D03*
Y516704D03*
Y524432D03*
X315187Y652457D03*
X304146D03*
X307146D03*
X315187Y661258D03*
X304146D03*
Y681100D03*
X315187D03*
Y671763D03*
X304146D03*
X307146D03*
Y681100D03*
Y661258D03*
X315187Y688828D03*
X304146D03*
Y697267D03*
X315187D03*
X307146D03*
Y688828D03*
X310194Y1020657D03*
X310078Y1007303D03*
X310274Y1001286D03*
X310143Y1014094D03*
X307143D03*
X307274Y1001286D03*
X307078Y1007303D03*
X307194Y1020657D03*
X310129Y1027081D03*
X309999Y1033718D03*
X306999D03*
X307129Y1027081D03*
X309159Y1184526D03*
Y1192254D03*
X300691Y1184526D03*
X292721Y1184312D03*
Y1192040D03*
X300691Y1192254D03*
X303691D03*
X295721Y1192040D03*
Y1184312D03*
X303691Y1184526D03*
X312159Y1192254D03*
Y1184526D03*
X309159Y1200693D03*
X300691D03*
X292721Y1200479D03*
X295721D03*
X303691Y1200693D03*
X312159D03*
X312823Y1472957D03*
X312464Y1480102D03*
X312823Y1466002D03*
Y1459086D03*
X295715Y1480099D03*
X295895Y1472954D03*
X304066D03*
X303886Y1480099D03*
X295895Y1459083D03*
Y1465999D03*
X304066D03*
Y1459083D03*
X301066D03*
Y1465999D03*
X292895D03*
Y1459083D03*
X300886Y1480099D03*
X301066Y1472954D03*
X292895D03*
X292715Y1480099D03*
X309823Y1459086D03*
Y1466002D03*
X309464Y1480102D03*
X309823Y1472957D03*
X312464Y1493973D03*
Y1487018D03*
X295715Y1487015D03*
Y1493970D03*
X303886D03*
Y1487015D03*
X300886D03*
Y1493970D03*
X292715D03*
Y1487015D03*
X309464Y1487018D03*
Y1493973D03*
X292614Y1864565D03*
X295754Y1917148D03*
X303349D03*
X295754Y1910232D03*
X303349D03*
X310215Y1910412D03*
X314810D03*
X307215D03*
X300349Y1910232D03*
X292754D03*
X300349Y1917148D03*
X292754D03*
X310215Y1917328D03*
X295754Y1924103D03*
X303349D03*
X310215Y1924283D03*
X307215D03*
X314810D03*
X300349Y1924103D03*
X292754D03*
X307215Y1917328D03*
X314810D03*
X332775Y318634D03*
X332693Y311980D03*
X329693D03*
X329775Y318634D03*
X332775Y335272D03*
Y342461D03*
Y325935D03*
X329775D03*
Y342461D03*
Y335272D03*
X332685Y348655D03*
X329685D03*
X325139Y516632D03*
Y524360D03*
X316791Y524432D03*
Y516704D03*
Y532871D03*
X325139Y532799D03*
X322139D03*
Y524360D03*
Y516632D03*
X318187Y652457D03*
Y671763D03*
Y681100D03*
Y661258D03*
Y697267D03*
Y688828D03*
X321235Y1020657D03*
X321315Y1001286D03*
X321119Y1007303D03*
X321184Y1014094D03*
X318184D03*
X318119Y1007303D03*
X318315Y1001286D03*
X318235Y1020657D03*
X321170Y1027081D03*
X321040Y1033718D03*
X318040D03*
X318170Y1027081D03*
X317936Y1192253D03*
Y1184525D03*
X320936D03*
Y1192253D03*
X323403Y1172804D03*
X317936Y1200692D03*
X320936D03*
X317810Y1910412D03*
Y1917328D03*
Y1924283D03*
X343816Y318634D03*
X343734Y311980D03*
X340734D03*
X340816Y318634D03*
X343816Y335272D03*
Y342461D03*
Y325935D03*
X340816D03*
Y342461D03*
Y335272D03*
X343726Y348655D03*
X340726D03*
G54D28*
X119920Y218071D03*
Y228071D03*
Y238071D03*
Y248071D03*
Y258071D03*
Y268071D03*
Y278071D03*
Y288071D03*
Y298071D03*
Y308071D03*
Y318071D03*
Y328071D03*
Y566102D03*
Y576102D03*
Y586102D03*
Y596102D03*
Y606102D03*
Y616102D03*
Y626102D03*
Y636102D03*
Y646102D03*
Y656102D03*
Y666102D03*
Y676102D03*
Y914134D03*
Y924134D03*
Y934134D03*
Y944134D03*
Y954134D03*
Y964134D03*
Y974134D03*
Y984134D03*
Y994134D03*
Y1004134D03*
Y1014134D03*
Y1024134D03*
Y1262165D03*
Y1272165D03*
Y1282165D03*
Y1292165D03*
Y1302165D03*
Y1312165D03*
Y1322165D03*
Y1332165D03*
Y1342165D03*
Y1352165D03*
Y1362165D03*
Y1372165D03*
Y1610197D03*
Y1620197D03*
Y1630197D03*
Y1640197D03*
Y1650197D03*
Y1660197D03*
Y1670197D03*
Y1680197D03*
Y1690197D03*
Y1700197D03*
Y1710197D03*
Y1720197D03*
Y1958228D03*
Y1968228D03*
Y1978228D03*
Y1988228D03*
Y1998228D03*
Y2008228D03*
Y2018228D03*
Y2028228D03*
Y2038228D03*
Y2048228D03*
Y2058228D03*
Y2068228D03*
X139920Y228071D03*
Y218071D03*
Y248071D03*
Y238071D03*
Y268071D03*
Y258071D03*
Y298071D03*
Y288071D03*
Y278071D03*
Y318071D03*
Y308071D03*
Y328071D03*
Y566102D03*
Y586102D03*
Y576102D03*
Y606102D03*
Y596102D03*
Y636102D03*
Y626102D03*
Y616102D03*
Y656102D03*
Y646102D03*
Y676102D03*
Y666102D03*
Y924134D03*
Y914134D03*
Y944134D03*
Y934134D03*
Y974134D03*
Y964134D03*
Y954134D03*
Y994134D03*
Y984134D03*
Y1024134D03*
Y1014134D03*
Y1004134D03*
Y1262165D03*
Y1282165D03*
Y1272165D03*
Y1312165D03*
Y1302165D03*
Y1292165D03*
Y1332165D03*
Y1322165D03*
Y1362165D03*
Y1352165D03*
Y1342165D03*
Y1372165D03*
Y1620197D03*
Y1610197D03*
Y1650197D03*
Y1640197D03*
Y1630197D03*
Y1670197D03*
Y1660197D03*
Y1700197D03*
Y1690197D03*
Y1680197D03*
Y1720197D03*
Y1710197D03*
Y1958228D03*
Y1988228D03*
Y1978228D03*
Y1968228D03*
Y2008228D03*
Y1998228D03*
Y2038228D03*
Y2028228D03*
Y2018228D03*
Y2058228D03*
Y2048228D03*
Y2068228D03*
G54D31*
X203542Y73105D03*
X204069Y152050D03*
X204137Y247568D03*
X204597Y331786D03*
X203541Y421732D03*
X204333Y506517D03*
X206668Y598130D03*
X204596Y681645D03*
X205626Y774526D03*
X205386Y856244D03*
X210091Y947202D03*
X209296Y1032544D03*
X205030Y1122856D03*
X205122Y1206233D03*
X205626Y1299104D03*
X204332Y1380966D03*
X203243Y1474162D03*
X204859Y1557277D03*
X205923Y1648177D03*
X205387Y1731351D03*
X205310Y1823227D03*
X204069Y1900420D03*
X205905Y1998730D03*
X205310Y2043388D03*
G54D22*
X45056Y1685410D03*
Y1701945D03*
Y1735016D03*
Y1751551D03*
Y1784622D03*
Y1801158D03*
%LPC*%
G75*
G54D36*
G01X-723776Y2987387D02*
Y-376795D01*
Y-489221D01*
X1782976D01*
Y-376795D01*
Y2987387D01*
X-723776D01*
G01X-4000Y-62500D02*
Y-137500D01*
X496000D01*
Y-62500D01*
X-4000D01*
G01X8000Y-127500D02*
Y-132500D01*
G01X6543Y-127500D02*
X9457D01*
G01X14367Y-132500D02*
X11833D01*
Y-127500D01*
X14367D01*
G01X13353Y-129917D02*
X11833D01*
G01X16933Y-127500D02*
Y-132500D01*
X19467D01*
G01X23300Y-132667D02*
X23173Y-132583D01*
Y-132417D01*
X23300Y-132333D01*
X23427Y-132417D01*
Y-132583D01*
X23300Y-132667D01*
G01Y-130417D02*
X23173Y-130333D01*
Y-130167D01*
X23300Y-130083D01*
X23427Y-130167D01*
Y-130333D01*
X23300Y-130417D01*
G01X28083Y-134167D02*
X27450Y-133333D01*
X27133Y-132500D01*
Y-129167D01*
X27450Y-128333D01*
X28083Y-127500D01*
G01X33500D02*
X32993Y-127667D01*
X32613Y-128083D01*
X32360Y-128583D01*
X32170Y-129250D01*
X32107Y-130000D01*
X32170Y-130750D01*
X32360Y-131417D01*
X32613Y-131917D01*
X32993Y-132333D01*
X33500Y-132500D01*
X34007Y-132333D01*
X34387Y-131917D01*
X34640Y-131417D01*
X34830Y-130750D01*
X34893Y-130000D01*
X34830Y-129250D01*
X34640Y-128583D01*
X34387Y-128083D01*
X34007Y-127667D01*
X33500Y-127500D01*
G01X37207Y-131500D02*
X37587Y-132083D01*
X38093Y-132417D01*
X38663Y-132500D01*
X39170Y-132417D01*
X39677Y-132000D01*
X39993Y-131500D01*
X40057Y-131000D01*
X39930Y-130417D01*
X39487Y-130000D01*
X39043Y-129833D01*
X38473D01*
G01X39043D02*
X39423Y-129583D01*
X39740Y-129167D01*
X39867Y-128667D01*
X39740Y-128167D01*
X39423Y-127750D01*
X38853Y-127500D01*
X38283Y-127583D01*
X37713Y-127917D01*
G01X44017Y-134167D02*
X44650Y-133333D01*
X44967Y-132500D01*
Y-129167D01*
X44650Y-128333D01*
X44017Y-127500D01*
G01X47407Y-131500D02*
X47787Y-132083D01*
X48293Y-132417D01*
X48863Y-132500D01*
X49370Y-132417D01*
X49877Y-132000D01*
X50193Y-131500D01*
X50257Y-131000D01*
X50130Y-130417D01*
X49687Y-130000D01*
X49243Y-129833D01*
X48673D01*
G01X49243D02*
X49623Y-129583D01*
X49940Y-129167D01*
X50067Y-128667D01*
X49940Y-128167D01*
X49623Y-127750D01*
X49053Y-127500D01*
X48483Y-127583D01*
X47913Y-127917D01*
G01X52697Y-128333D02*
X53077Y-127833D01*
X53520Y-127583D01*
X54027Y-127500D01*
X54660Y-127667D01*
X55103Y-128083D01*
X55230Y-128583D01*
X55167Y-129083D01*
X54913Y-129500D01*
X53647Y-130333D01*
X53077Y-130917D01*
X52697Y-131750D01*
X52570Y-132500D01*
X55230D01*
G01X58873D02*
X59000Y-131417D01*
X59190Y-130500D01*
X59443Y-129667D01*
X59760Y-128750D01*
X60267Y-127500D01*
X57733D01*
G01X63277Y-130833D02*
X64923D01*
G01X67997Y-128333D02*
X68377Y-127833D01*
X68820Y-127583D01*
X69327Y-127500D01*
X69960Y-127667D01*
X70403Y-128083D01*
X70530Y-128583D01*
X70467Y-129083D01*
X70213Y-129500D01*
X68947Y-130333D01*
X68377Y-130917D01*
X67997Y-131750D01*
X67870Y-132500D01*
X70530D01*
G01X72907Y-131500D02*
X73287Y-132083D01*
X73793Y-132417D01*
X74363Y-132500D01*
X74870Y-132417D01*
X75377Y-132000D01*
X75693Y-131500D01*
X75757Y-131000D01*
X75630Y-130417D01*
X75187Y-130000D01*
X74743Y-129833D01*
X74173D01*
G01X74743D02*
X75123Y-129583D01*
X75440Y-129167D01*
X75567Y-128667D01*
X75440Y-128167D01*
X75123Y-127750D01*
X74553Y-127500D01*
X73983Y-127583D01*
X73413Y-127917D01*
G01X80160Y-132500D02*
Y-127500D01*
X77817Y-131083D01*
X80983D01*
G01X83107Y-131750D02*
X83487Y-132167D01*
X83930Y-132417D01*
X84500Y-132500D01*
X85070Y-132333D01*
X85513Y-132000D01*
X85830Y-131417D01*
X85893Y-130750D01*
X85767Y-130083D01*
X85450Y-129667D01*
X85007Y-129333D01*
X84563Y-129250D01*
X84120Y-129333D01*
X83550Y-129667D01*
X83740Y-127500D01*
X85450D01*
G01X93497Y-132500D02*
Y-127500D01*
X95903D01*
G01X95017Y-129917D02*
X93497D01*
G01X98217Y-132500D02*
X99800Y-127500D01*
X101383Y-132500D01*
G01X100813Y-130750D02*
X98787D01*
G01X103570Y-132500D02*
X106230Y-127500D01*
G01X103570D02*
X106230Y-132500D01*
G01X110000Y-132667D02*
X109873Y-132583D01*
Y-132417D01*
X110000Y-132333D01*
X110127Y-132417D01*
Y-132583D01*
X110000Y-132667D01*
G01Y-130417D02*
X109873Y-130333D01*
Y-130167D01*
X110000Y-130083D01*
X110127Y-130167D01*
Y-130333D01*
X110000Y-130417D01*
G01X114783Y-134167D02*
X114150Y-133333D01*
X113833Y-132500D01*
Y-129167D01*
X114150Y-128333D01*
X114783Y-127500D01*
G01X120200D02*
X119693Y-127667D01*
X119313Y-128083D01*
X119060Y-128583D01*
X118870Y-129250D01*
X118807Y-130000D01*
X118870Y-130750D01*
X119060Y-131417D01*
X119313Y-131917D01*
X119693Y-132333D01*
X120200Y-132500D01*
X120707Y-132333D01*
X121087Y-131917D01*
X121340Y-131417D01*
X121530Y-130750D01*
X121593Y-130000D01*
X121530Y-129250D01*
X121340Y-128583D01*
X121087Y-128083D01*
X120707Y-127667D01*
X120200Y-127500D01*
G01X123907Y-131500D02*
X124287Y-132083D01*
X124793Y-132417D01*
X125363Y-132500D01*
X125870Y-132417D01*
X126377Y-132000D01*
X126693Y-131500D01*
X126757Y-131000D01*
X126630Y-130417D01*
X126187Y-130000D01*
X125743Y-129833D01*
X125173D01*
G01X125743D02*
X126123Y-129583D01*
X126440Y-129167D01*
X126567Y-128667D01*
X126440Y-128167D01*
X126123Y-127750D01*
X125553Y-127500D01*
X124983Y-127583D01*
X124413Y-127917D01*
G01X130717Y-134167D02*
X131350Y-133333D01*
X131667Y-132500D01*
Y-129167D01*
X131350Y-128333D01*
X130717Y-127500D01*
G01X134107Y-131500D02*
X134487Y-132083D01*
X134993Y-132417D01*
X135563Y-132500D01*
X136070Y-132417D01*
X136577Y-132000D01*
X136893Y-131500D01*
X136957Y-131000D01*
X136830Y-130417D01*
X136387Y-130000D01*
X135943Y-129833D01*
X135373D01*
G01X135943D02*
X136323Y-129583D01*
X136640Y-129167D01*
X136767Y-128667D01*
X136640Y-128167D01*
X136323Y-127750D01*
X135753Y-127500D01*
X135183Y-127583D01*
X134613Y-127917D01*
G01X139523Y-131917D02*
X139967Y-132333D01*
X140473Y-132500D01*
X140980Y-132333D01*
X141423Y-131833D01*
X141740Y-131083D01*
X141867Y-130333D01*
Y-129417D01*
X141740Y-128667D01*
X141423Y-128000D01*
X141043Y-127667D01*
X140600Y-127500D01*
X140093Y-127667D01*
X139713Y-128000D01*
X139460Y-128500D01*
X139333Y-129167D01*
X139460Y-129750D01*
X139777Y-130333D01*
X140157Y-130667D01*
X140600Y-130750D01*
X141107Y-130583D01*
X141487Y-130167D01*
X141867Y-129417D01*
G01X145573Y-132500D02*
X145700Y-131417D01*
X145890Y-130500D01*
X146143Y-129667D01*
X146460Y-128750D01*
X146967Y-127500D01*
X144433D01*
G01X149977Y-130833D02*
X151623D01*
G01X154507Y-131500D02*
X154887Y-132083D01*
X155393Y-132417D01*
X155963Y-132500D01*
X156470Y-132417D01*
X156977Y-132000D01*
X157293Y-131500D01*
X157357Y-131000D01*
X157230Y-130417D01*
X156787Y-130000D01*
X156343Y-129833D01*
X155773D01*
G01X156343D02*
X156723Y-129583D01*
X157040Y-129167D01*
X157167Y-128667D01*
X157040Y-128167D01*
X156723Y-127750D01*
X156153Y-127500D01*
X155583Y-127583D01*
X155013Y-127917D01*
G01X159797Y-130417D02*
X160240Y-129833D01*
X160620Y-129500D01*
X161127Y-129333D01*
X161570Y-129500D01*
X161887Y-129833D01*
X162140Y-130333D01*
X162203Y-130917D01*
X162140Y-131417D01*
X161887Y-131917D01*
X161507Y-132333D01*
X161063Y-132500D01*
X160557Y-132333D01*
X160113Y-131833D01*
X159860Y-131083D01*
X159797Y-130250D01*
X159923Y-129167D01*
X160113Y-128583D01*
X160430Y-128000D01*
X160873Y-127583D01*
X161317Y-127500D01*
X161760Y-127667D01*
X162077Y-128083D01*
G01X166100Y-132500D02*
Y-127500D01*
X165340Y-128500D01*
G01Y-132500D02*
X166860D01*
G01X171960D02*
Y-127500D01*
X169617Y-131083D01*
X172783D01*
G01X191000Y-62500D02*
Y-137500D01*
G01Y-112500D02*
X294000D01*
Y-87500D01*
G01X191000D02*
X294000D01*
G01X301507Y-122500D02*
Y-117500D01*
X302773D01*
X303280Y-117750D01*
X303660Y-118083D01*
X303977Y-118583D01*
X304230Y-119167D01*
X304293Y-120000D01*
X304230Y-120833D01*
X303977Y-121417D01*
X303660Y-121917D01*
X303280Y-122250D01*
X302773Y-122500D01*
X301507D01*
G01X306417D02*
X308000Y-117500D01*
X309583Y-122500D01*
G01X309013Y-120750D02*
X306987D01*
G01X313100Y-117500D02*
Y-122500D01*
G01X311643Y-117500D02*
X314557D01*
G01X319467Y-122500D02*
X316933D01*
Y-117500D01*
X319467D01*
G01X318453Y-119917D02*
X316933D01*
G01X323300Y-122667D02*
X323173Y-122583D01*
Y-122417D01*
X323300Y-122333D01*
X323427Y-122417D01*
Y-122583D01*
X323300Y-122667D01*
G01Y-120417D02*
X323173Y-120333D01*
Y-120167D01*
X323300Y-120083D01*
X323427Y-120167D01*
Y-120333D01*
X323300Y-120417D01*
G01X296000Y-62500D02*
Y-137500D01*
G01X294000Y-62500D02*
Y-137500D01*
G01X301633Y-97500D02*
Y-92500D01*
X303153D01*
X303660Y-92750D01*
X304040Y-93333D01*
X304167Y-94000D01*
X304040Y-94667D01*
X303723Y-95167D01*
X303153Y-95417D01*
X301633D01*
G01X306860Y-97667D02*
X309140Y-92500D01*
G01X311643Y-97500D02*
Y-92500D01*
X314557Y-97500D01*
Y-92500D01*
G01X318200Y-97667D02*
X318073Y-97583D01*
Y-97417D01*
X318200Y-97333D01*
X318327Y-97417D01*
Y-97583D01*
X318200Y-97667D01*
G01Y-95417D02*
X318073Y-95333D01*
Y-95167D01*
X318200Y-95083D01*
X318327Y-95167D01*
Y-95333D01*
X318200Y-95417D01*
G01X296000Y-112500D02*
X496000D01*
G01X301633Y-72500D02*
Y-67500D01*
X303153D01*
X303660Y-67750D01*
X304040Y-68333D01*
X304167Y-69000D01*
X304040Y-69667D01*
X303723Y-70167D01*
X303153Y-70417D01*
X301633D01*
G01X306733Y-72500D02*
Y-67500D01*
X308317D01*
X308823Y-67750D01*
X309140Y-68083D01*
X309267Y-68750D01*
X309140Y-69417D01*
X308760Y-69833D01*
X308317Y-70083D01*
X306733D01*
G01X308317D02*
X309267Y-72500D01*
G01X313100D02*
X312593Y-72417D01*
X312150Y-72083D01*
X311770Y-71583D01*
X311517Y-71000D01*
X311390Y-70333D01*
Y-69667D01*
X311517Y-69000D01*
X311770Y-68417D01*
X312150Y-67917D01*
X312593Y-67583D01*
X313100Y-67500D01*
X313607Y-67583D01*
X314050Y-67917D01*
X314430Y-68417D01*
X314683Y-69000D01*
X314810Y-69667D01*
Y-70333D01*
X314683Y-71000D01*
X314430Y-71583D01*
X314050Y-72083D01*
X313607Y-72417D01*
X313100Y-72500D01*
G01X316933Y-71500D02*
X317250Y-72000D01*
X317630Y-72333D01*
X318073Y-72500D01*
X318580Y-72333D01*
X318960Y-72000D01*
X319340Y-71500D01*
X319467Y-70833D01*
Y-67500D01*
G01X324567Y-72500D02*
X322033D01*
Y-67500D01*
X324567D01*
G01X323553Y-69917D02*
X322033D01*
G01X329793Y-67917D02*
X329413Y-67667D01*
X328970Y-67500D01*
X328463D01*
X327893Y-67750D01*
X327450Y-68167D01*
X327133Y-68667D01*
X326880Y-69500D01*
X326817Y-70250D01*
X326943Y-71000D01*
X327133Y-71500D01*
X327513Y-72000D01*
X327957Y-72333D01*
X328400Y-72500D01*
X328843D01*
X329287Y-72333D01*
X329667Y-72083D01*
X329983Y-71750D01*
G01X333500Y-67500D02*
Y-72500D01*
G01X332043Y-67500D02*
X334957D01*
G01X338600Y-72667D02*
X338473Y-72583D01*
Y-72417D01*
X338600Y-72333D01*
X338727Y-72417D01*
Y-72583D01*
X338600Y-72667D01*
G01Y-70417D02*
X338473Y-70333D01*
Y-70167D01*
X338600Y-70083D01*
X338727Y-70167D01*
Y-70333D01*
X338600Y-70417D01*
G01X296000Y-87500D02*
X496000D01*
G01X411000Y-112500D02*
Y-137500D01*
G01X416633Y-122500D02*
Y-117500D01*
X418217D01*
X418723Y-117750D01*
X419040Y-118083D01*
X419167Y-118750D01*
X419040Y-119417D01*
X418660Y-119833D01*
X418217Y-120083D01*
X416633D01*
G01X418217D02*
X419167Y-122500D01*
G01X424267D02*
X421733D01*
Y-117500D01*
X424267D01*
G01X423253Y-119917D02*
X421733D01*
G01X426517Y-117500D02*
X428100Y-122500D01*
X429683Y-117500D01*
G01X433200Y-122667D02*
X433073Y-122583D01*
Y-122417D01*
X433200Y-122333D01*
X433327Y-122417D01*
Y-122583D01*
X433200Y-122667D01*
G01Y-120417D02*
X433073Y-120333D01*
Y-120167D01*
X433200Y-120083D01*
X433327Y-120167D01*
Y-120333D01*
X433200Y-120417D01*
G01X460000Y-112500D02*
Y-137500D01*
G01X-723776Y2987387D02*
Y-376795D01*
Y-489221D01*
X1782976D01*
Y-376795D01*
Y2987387D01*
X-723776D01*
G01X6705Y-124160D02*
X7332Y-124685D01*
X8037Y-125000D01*
X8663D01*
X9290Y-124685D01*
X9760Y-124160D01*
X9995Y-123425D01*
X9838Y-122690D01*
X9447Y-122060D01*
X8742Y-121640D01*
X7802Y-121430D01*
X7253Y-121010D01*
X7018Y-120275D01*
X7175Y-119540D01*
X7567Y-119015D01*
X8115Y-118700D01*
X8663D01*
X9212Y-118910D01*
X9682Y-119435D01*
G01X13005Y-125000D02*
Y-118700D01*
G01X16295D02*
Y-125000D01*
G01Y-121850D02*
X13005D01*
G01X20010Y-118700D02*
X21890D01*
G01X20950D02*
Y-125000D01*
G01X20010D02*
X21890D01*
G01X28817D02*
X25683D01*
Y-118700D01*
X28817D01*
G01X27563Y-121745D02*
X25683D01*
G01X31748Y-125000D02*
Y-118700D01*
X35352Y-125000D01*
Y-118700D01*
G01X39693Y-126155D02*
X40007Y-124790D01*
G01X46150Y-118700D02*
Y-125000D01*
G01X44348Y-118700D02*
X47952D01*
G01X50492Y-125000D02*
X52450Y-118700D01*
X54408Y-125000D01*
G01X53703Y-122795D02*
X51197D01*
G01X57810Y-118700D02*
X59690D01*
G01X58750D02*
Y-125000D01*
G01X57810D02*
X59690D01*
G01X62700Y-118700D02*
X63797Y-125000D01*
X65050Y-118700D01*
X66303Y-125000D01*
X67400Y-118700D01*
G01X69392Y-125000D02*
X71350Y-118700D01*
X73308Y-125000D01*
G01X72603Y-122795D02*
X70097D01*
G01X75848Y-125000D02*
Y-118700D01*
X79452Y-125000D01*
Y-118700D01*
G01X88683Y-125000D02*
Y-118700D01*
X90642D01*
X91268Y-119015D01*
X91660Y-119435D01*
X91817Y-120275D01*
X91660Y-121115D01*
X91190Y-121640D01*
X90642Y-121955D01*
X88683D01*
G01X90642D02*
X91817Y-125000D01*
G01X96550Y-125210D02*
X96393Y-125105D01*
Y-124895D01*
X96550Y-124790D01*
X96707Y-124895D01*
Y-125105D01*
X96550Y-125210D01*
G01X102850Y-125000D02*
X102223Y-124895D01*
X101675Y-124475D01*
X101205Y-123845D01*
X100892Y-123110D01*
X100735Y-122270D01*
Y-121430D01*
X100892Y-120590D01*
X101205Y-119855D01*
X101675Y-119225D01*
X102223Y-118805D01*
X102850Y-118700D01*
X103477Y-118805D01*
X104025Y-119225D01*
X104495Y-119855D01*
X104808Y-120590D01*
X104965Y-121430D01*
Y-122270D01*
X104808Y-123110D01*
X104495Y-123845D01*
X104025Y-124475D01*
X103477Y-124895D01*
X102850Y-125000D01*
G01X109150Y-125210D02*
X108993Y-125105D01*
Y-124895D01*
X109150Y-124790D01*
X109307Y-124895D01*
Y-125105D01*
X109150Y-125210D01*
G01X117173Y-119225D02*
X116703Y-118910D01*
X116155Y-118700D01*
X115528D01*
X114823Y-119015D01*
X114275Y-119540D01*
X113883Y-120170D01*
X113570Y-121220D01*
X113492Y-122165D01*
X113648Y-123110D01*
X113883Y-123740D01*
X114353Y-124370D01*
X114902Y-124790D01*
X115450Y-125000D01*
X115998D01*
X116547Y-124790D01*
X117017Y-124475D01*
X117408Y-124055D01*
G01X121750Y-125210D02*
X121593Y-125105D01*
Y-124895D01*
X121750Y-124790D01*
X121907Y-124895D01*
Y-125105D01*
X121750Y-125210D01*
G01X6627Y-115000D02*
Y-108700D01*
G01X9603D02*
X6627Y-112585D01*
G01X10073Y-115000D02*
X7958Y-110800D01*
G01X12927Y-108700D02*
Y-113215D01*
X13240Y-114160D01*
X13867Y-114790D01*
X14650Y-115000D01*
X15433Y-114790D01*
X16060Y-114160D01*
X16373Y-113215D01*
Y-108700D01*
G01X22517Y-115000D02*
X19383D01*
Y-108700D01*
X22517D01*
G01X21263Y-111745D02*
X19383D01*
G01X26310Y-108700D02*
X28190D01*
G01X27250D02*
Y-115000D01*
G01X26310D02*
X28190D01*
G01X38205Y-114160D02*
X38832Y-114685D01*
X39537Y-115000D01*
X40163D01*
X40790Y-114685D01*
X41260Y-114160D01*
X41495Y-113425D01*
X41338Y-112690D01*
X40947Y-112060D01*
X40242Y-111640D01*
X39302Y-111430D01*
X38753Y-111010D01*
X38518Y-110275D01*
X38675Y-109540D01*
X39067Y-109015D01*
X39615Y-108700D01*
X40163D01*
X40712Y-108910D01*
X41182Y-109435D01*
G01X44505Y-115000D02*
Y-108700D01*
G01X47795D02*
Y-115000D01*
G01Y-111850D02*
X44505D01*
G01X50492Y-115000D02*
X52450Y-108700D01*
X54408Y-115000D01*
G01X53703Y-112795D02*
X51197D01*
G01X56948Y-115000D02*
Y-108700D01*
X60552Y-115000D01*
Y-108700D01*
G01X69705Y-115000D02*
Y-108700D01*
G01X72995D02*
Y-115000D01*
G01Y-111850D02*
X69705D01*
G01X76005Y-114160D02*
X76632Y-114685D01*
X77337Y-115000D01*
X77963D01*
X78590Y-114685D01*
X79060Y-114160D01*
X79295Y-113425D01*
X79138Y-112690D01*
X78747Y-112060D01*
X78042Y-111640D01*
X77102Y-111430D01*
X76553Y-111010D01*
X76318Y-110275D01*
X76475Y-109540D01*
X76867Y-109015D01*
X77415Y-108700D01*
X77963D01*
X78512Y-108910D01*
X78982Y-109435D01*
G01X83010Y-108700D02*
X84890D01*
G01X83950D02*
Y-115000D01*
G01X83010D02*
X84890D01*
G01X88292D02*
X90250Y-108700D01*
X92208Y-115000D01*
G01X91503Y-112795D02*
X88997D01*
G01X94748Y-115000D02*
Y-108700D01*
X98352Y-115000D01*
Y-108700D01*
G01X103320Y-111850D02*
X104887D01*
Y-113740D01*
X104417Y-114370D01*
X103868Y-114790D01*
X103085Y-115000D01*
X102302Y-114790D01*
X101753Y-114370D01*
X101283Y-113740D01*
X100970Y-113005D01*
X100813Y-112165D01*
Y-111430D01*
X100970Y-110800D01*
X101283Y-110065D01*
X101753Y-109435D01*
X102223Y-109015D01*
X102850Y-108700D01*
X103398D01*
X104025Y-108910D01*
X104495Y-109330D01*
G01X108993Y-116155D02*
X109307Y-114790D01*
G01X115450Y-108700D02*
Y-115000D01*
G01X113648Y-108700D02*
X117252D01*
G01X119792Y-115000D02*
X121750Y-108700D01*
X123708Y-115000D01*
G01X123003Y-112795D02*
X120497D01*
G01X128050Y-115000D02*
X127423Y-114895D01*
X126875Y-114475D01*
X126405Y-113845D01*
X126092Y-113110D01*
X125935Y-112270D01*
Y-111430D01*
X126092Y-110590D01*
X126405Y-109855D01*
X126875Y-109225D01*
X127423Y-108805D01*
X128050Y-108700D01*
X128677Y-108805D01*
X129225Y-109225D01*
X129695Y-109855D01*
X130008Y-110590D01*
X130165Y-111430D01*
Y-112270D01*
X130008Y-113110D01*
X129695Y-113845D01*
X129225Y-114475D01*
X128677Y-114895D01*
X128050Y-115000D01*
G01X140650D02*
Y-112165D01*
X139083Y-108700D01*
G01X142217D02*
X140650Y-112165D01*
G01X145227Y-108700D02*
Y-113215D01*
X145540Y-114160D01*
X146167Y-114790D01*
X146950Y-115000D01*
X147733Y-114790D01*
X148360Y-114160D01*
X148673Y-113215D01*
Y-108700D01*
G01X151292Y-115000D02*
X153250Y-108700D01*
X155208Y-115000D01*
G01X154503Y-112795D02*
X151997D01*
G01X157748Y-115000D02*
Y-108700D01*
X161352Y-115000D01*
Y-108700D01*
G01X30650Y-92300D02*
X28130Y-91883D01*
X25925Y-90217D01*
X24035Y-87717D01*
X22775Y-84800D01*
X22145Y-81467D01*
Y-78133D01*
X22775Y-74800D01*
X24035Y-71883D01*
X25925Y-69384D01*
X28130Y-67717D01*
X30650Y-67300D01*
X33170Y-67717D01*
X35375Y-69384D01*
X37265Y-71883D01*
X38525Y-74800D01*
X39155Y-78133D01*
Y-81467D01*
X38525Y-84800D01*
X37265Y-87717D01*
X35375Y-90217D01*
X33170Y-91883D01*
X30650Y-92300D01*
G01X33170Y-85633D02*
X36950Y-92300D01*
G01X50495Y-75634D02*
Y-87300D01*
X51755Y-90217D01*
X53645Y-91883D01*
X55850Y-92300D01*
X58055Y-91883D01*
X59945Y-90217D01*
X61205Y-87300D01*
G01Y-92300D02*
Y-75634D01*
G01X86720Y-92300D02*
Y-75634D01*
G01Y-78550D02*
X85460Y-76884D01*
X83570Y-76050D01*
X81365Y-75634D01*
X79160Y-76467D01*
X77270Y-78133D01*
X76010Y-80634D01*
X75380Y-83967D01*
X76010Y-87300D01*
X77270Y-89801D01*
X79160Y-91467D01*
X81365Y-92300D01*
X83570Y-91883D01*
X85460Y-90634D01*
X86720Y-88967D01*
G01X100895Y-92300D02*
Y-75634D01*
G01Y-79800D02*
X102155Y-77717D01*
X104045Y-76050D01*
X106565Y-75634D01*
X108770Y-76050D01*
X110660Y-77717D01*
X111605Y-80634D01*
Y-92300D01*
G01X131450Y-67300D02*
Y-92300D01*
G01X127040Y-75634D02*
X135860D01*
G01X162320Y-92300D02*
Y-75634D01*
G01Y-78550D02*
X161060Y-76884D01*
X159170Y-76050D01*
X156965Y-75634D01*
X154760Y-76467D01*
X152870Y-78133D01*
X151610Y-80634D01*
X150980Y-83967D01*
X151610Y-87300D01*
X152870Y-89801D01*
X154760Y-91467D01*
X156965Y-92300D01*
X159170Y-91883D01*
X161060Y-90634D01*
X162320Y-88967D01*
G01X6548Y-105000D02*
Y-98700D01*
X10152Y-105000D01*
Y-98700D01*
G01X14650Y-105000D02*
X14023Y-104895D01*
X13475Y-104475D01*
X13005Y-103845D01*
X12692Y-103110D01*
X12535Y-102270D01*
Y-101430D01*
X12692Y-100590D01*
X13005Y-99855D01*
X13475Y-99225D01*
X14023Y-98805D01*
X14650Y-98700D01*
X15277Y-98805D01*
X15825Y-99225D01*
X16295Y-99855D01*
X16608Y-100590D01*
X16765Y-101430D01*
Y-102270D01*
X16608Y-103110D01*
X16295Y-103845D01*
X15825Y-104475D01*
X15277Y-104895D01*
X14650Y-105000D01*
G01X20950Y-105210D02*
X20793Y-105105D01*
Y-104895D01*
X20950Y-104790D01*
X21107Y-104895D01*
Y-105105D01*
X20950Y-105210D01*
G01X27250Y-105000D02*
Y-98700D01*
X26310Y-99960D01*
G01Y-105000D02*
X28190D01*
G01X33550D02*
X34098Y-104895D01*
X34725Y-104580D01*
X35117Y-104055D01*
X35273Y-103320D01*
X35117Y-102585D01*
X34647Y-101955D01*
X33942Y-101640D01*
X33158D01*
X32688Y-101430D01*
X32297Y-100905D01*
X32140Y-100170D01*
X32375Y-99435D01*
X32923Y-98910D01*
X33550Y-98700D01*
X34177Y-98910D01*
X34725Y-99435D01*
X34960Y-100170D01*
X34803Y-100905D01*
X34412Y-101430D01*
X33942Y-101640D01*
X33158D01*
X32453Y-101955D01*
X31983Y-102585D01*
X31827Y-103320D01*
X31983Y-104055D01*
X32375Y-104580D01*
X33002Y-104895D01*
X33550Y-105000D01*
G01X39850D02*
X40398Y-104895D01*
X41025Y-104580D01*
X41417Y-104055D01*
X41573Y-103320D01*
X41417Y-102585D01*
X40947Y-101955D01*
X40242Y-101640D01*
X39458D01*
X38988Y-101430D01*
X38597Y-100905D01*
X38440Y-100170D01*
X38675Y-99435D01*
X39223Y-98910D01*
X39850Y-98700D01*
X40477Y-98910D01*
X41025Y-99435D01*
X41260Y-100170D01*
X41103Y-100905D01*
X40712Y-101430D01*
X40242Y-101640D01*
X39458D01*
X38753Y-101955D01*
X38283Y-102585D01*
X38127Y-103320D01*
X38283Y-104055D01*
X38675Y-104580D01*
X39302Y-104895D01*
X39850Y-105000D01*
G01X45993Y-106155D02*
X46307Y-104790D01*
G01X50100Y-98700D02*
X51197Y-105000D01*
X52450Y-98700D01*
X53703Y-105000D01*
X54800Y-98700D01*
G01X60317Y-105000D02*
X57183D01*
Y-98700D01*
X60317D01*
G01X59063Y-101745D02*
X57183D01*
G01X63248Y-105000D02*
Y-98700D01*
X66852Y-105000D01*
Y-98700D01*
G01X76005Y-105000D02*
Y-98700D01*
G01X79295D02*
Y-105000D01*
G01Y-101850D02*
X76005D01*
G01X81600Y-98700D02*
X82697Y-105000D01*
X83950Y-98700D01*
X85203Y-105000D01*
X86300Y-98700D01*
G01X88292Y-105000D02*
X90250Y-98700D01*
X92208Y-105000D01*
G01X91503Y-102795D02*
X88997D01*
G01X101362Y-99750D02*
X101832Y-99120D01*
X102380Y-98805D01*
X103007Y-98700D01*
X103790Y-98910D01*
X104338Y-99435D01*
X104495Y-100065D01*
X104417Y-100695D01*
X104103Y-101220D01*
X102537Y-102270D01*
X101832Y-103005D01*
X101362Y-104055D01*
X101205Y-105000D01*
X104495D01*
G01X107348D02*
Y-98700D01*
X110952Y-105000D01*
Y-98700D01*
G01X113727Y-105000D02*
Y-98700D01*
X115293D01*
X115920Y-99015D01*
X116390Y-99435D01*
X116782Y-100065D01*
X117095Y-100800D01*
X117173Y-101850D01*
X117095Y-102900D01*
X116782Y-103635D01*
X116390Y-104265D01*
X115920Y-104685D01*
X115293Y-105000D01*
X113727D01*
G01X126483D02*
Y-98700D01*
X128442D01*
X129068Y-99015D01*
X129460Y-99435D01*
X129617Y-100275D01*
X129460Y-101115D01*
X128990Y-101640D01*
X128442Y-101955D01*
X126483D01*
G01X128442D02*
X129617Y-105000D01*
G01X132627D02*
Y-98700D01*
X134193D01*
X134820Y-99015D01*
X135290Y-99435D01*
X135682Y-100065D01*
X135995Y-100800D01*
X136073Y-101850D01*
X135995Y-102900D01*
X135682Y-103635D01*
X135290Y-104265D01*
X134820Y-104685D01*
X134193Y-105000D01*
X132627D01*
G01X140650Y-105210D02*
X140493Y-105105D01*
Y-104895D01*
X140650Y-104790D01*
X140807Y-104895D01*
Y-105105D01*
X140650Y-105210D01*
G01X202000Y-72000D02*
Y-80000D01*
X206000D01*
G01X213800D02*
Y-74667D01*
G01Y-75600D02*
X213400Y-75067D01*
X212800Y-74800D01*
X212100Y-74667D01*
X211400Y-74933D01*
X210800Y-75467D01*
X210400Y-76267D01*
X210200Y-77333D01*
X210400Y-78400D01*
X210800Y-79200D01*
X211400Y-79733D01*
X212100Y-80000D01*
X212800Y-79867D01*
X213400Y-79467D01*
X213800Y-78934D01*
G01X217900Y-82400D02*
X218500Y-82667D01*
X219300Y-82400D01*
X219800Y-81867D01*
X220200Y-81200D01*
X220800Y-79067D01*
X222100Y-74667D01*
G01X218900D02*
X220800Y-79067D01*
G01X226500Y-76400D02*
X229700D01*
X229400Y-75467D01*
X228900Y-74933D01*
X228200Y-74667D01*
X227500Y-74800D01*
X226900Y-75200D01*
X226500Y-76133D01*
X226300Y-76934D01*
Y-77733D01*
X226500Y-78533D01*
X227000Y-79333D01*
X227600Y-79867D01*
X228300Y-80000D01*
X229000Y-79733D01*
X229700Y-78934D01*
G01X234600Y-80000D02*
Y-74667D01*
G01Y-75733D02*
X235100Y-75200D01*
X235600Y-74800D01*
X236300Y-74667D01*
X236800Y-74800D01*
X237400Y-75200D01*
G01X225500Y-122000D02*
Y-130000D01*
G01X223200Y-122000D02*
X227800D01*
G01X233500Y-124667D02*
Y-130000D01*
G01Y-122533D02*
X233300Y-122400D01*
Y-122133D01*
X233500Y-122000D01*
X233700Y-122133D01*
Y-122400D01*
X233500Y-122533D01*
G01X239800Y-130000D02*
Y-124667D01*
G01Y-126000D02*
X240200Y-125333D01*
X240800Y-124800D01*
X241600Y-124667D01*
X242300Y-124800D01*
X242900Y-125333D01*
X243200Y-126267D01*
Y-130000D01*
G01X251300D02*
Y-124667D01*
G01Y-125600D02*
X250900Y-125067D01*
X250300Y-124800D01*
X249600Y-124667D01*
X248900Y-124933D01*
X248300Y-125467D01*
X247900Y-126267D01*
X247700Y-127333D01*
X247900Y-128400D01*
X248300Y-129200D01*
X248900Y-129733D01*
X249600Y-130000D01*
X250300Y-129867D01*
X250900Y-129467D01*
X251300Y-128934D01*
G01X233000Y-97000D02*
X235500Y-105000D01*
X238000Y-97000D01*
G01X245700Y-97667D02*
X245100Y-97267D01*
X244400Y-97000D01*
X243600D01*
X242700Y-97400D01*
X242000Y-98067D01*
X241500Y-98867D01*
X241100Y-100200D01*
X241000Y-101400D01*
X241200Y-102600D01*
X241500Y-103400D01*
X242100Y-104200D01*
X242800Y-104733D01*
X243500Y-105000D01*
X244200D01*
X244900Y-104733D01*
X245500Y-104333D01*
X246000Y-103800D01*
G01X253700Y-97667D02*
X253100Y-97267D01*
X252400Y-97000D01*
X251600D01*
X250700Y-97400D01*
X250000Y-98067D01*
X249500Y-98867D01*
X249100Y-100200D01*
X249000Y-101400D01*
X249200Y-102600D01*
X249500Y-103400D01*
X250100Y-104200D01*
X250800Y-104733D01*
X251500Y-105000D01*
X252200D01*
X252900Y-104733D01*
X253500Y-104333D01*
X254000Y-103800D01*
G01X259500Y-105000D02*
Y-97000D01*
X258300Y-98600D01*
G01Y-105000D02*
X260700D01*
G01X253300Y-78800D02*
X253900Y-79467D01*
X254600Y-79867D01*
X255500Y-80000D01*
X256400Y-79733D01*
X257100Y-79200D01*
X257600Y-78267D01*
X257700Y-77200D01*
X257500Y-76133D01*
X257000Y-75467D01*
X256300Y-74933D01*
X255600Y-74800D01*
X254900Y-74933D01*
X254000Y-75467D01*
X254300Y-72000D01*
X257000D01*
G01X328600Y-123333D02*
X329200Y-122533D01*
X329900Y-122133D01*
X330700Y-122000D01*
X331700Y-122267D01*
X332400Y-122933D01*
X332600Y-123733D01*
X332500Y-124534D01*
X332100Y-125200D01*
X330100Y-126533D01*
X329200Y-127467D01*
X328600Y-128800D01*
X328400Y-130000D01*
X332600D01*
G01X338500Y-122000D02*
X337700Y-122267D01*
X337100Y-122933D01*
X336700Y-123733D01*
X336400Y-124800D01*
X336300Y-126000D01*
X336400Y-127200D01*
X336700Y-128267D01*
X337100Y-129067D01*
X337700Y-129733D01*
X338500Y-130000D01*
X339300Y-129733D01*
X339900Y-129067D01*
X340300Y-128267D01*
X340600Y-127200D01*
X340700Y-126000D01*
X340600Y-124800D01*
X340300Y-123733D01*
X339900Y-122933D01*
X339300Y-122267D01*
X338500Y-122000D01*
G01X346500Y-130000D02*
Y-122000D01*
X345300Y-123600D01*
G01Y-130000D02*
X347700D01*
G01X352300Y-128400D02*
X352900Y-129333D01*
X353700Y-129867D01*
X354600Y-130000D01*
X355400Y-129867D01*
X356200Y-129200D01*
X356700Y-128400D01*
X356800Y-127600D01*
X356600Y-126667D01*
X355900Y-126000D01*
X355200Y-125733D01*
X354300D01*
G01X355200D02*
X355800Y-125333D01*
X356300Y-124667D01*
X356500Y-123867D01*
X356300Y-123067D01*
X355800Y-122400D01*
X354900Y-122000D01*
X354000Y-122133D01*
X353100Y-122667D01*
G01X360700Y-130267D02*
X364300Y-122000D01*
G01X370500D02*
X369700Y-122267D01*
X369100Y-122933D01*
X368700Y-123733D01*
X368400Y-124800D01*
X368300Y-126000D01*
X368400Y-127200D01*
X368700Y-128267D01*
X369100Y-129067D01*
X369700Y-129733D01*
X370500Y-130000D01*
X371300Y-129733D01*
X371900Y-129067D01*
X372300Y-128267D01*
X372600Y-127200D01*
X372700Y-126000D01*
X372600Y-124800D01*
X372300Y-123733D01*
X371900Y-122933D01*
X371300Y-122267D01*
X370500Y-122000D01*
G01X378500Y-130000D02*
Y-122000D01*
X377300Y-123600D01*
G01Y-130000D02*
X379700D01*
G01X384700Y-130267D02*
X388300Y-122000D01*
G01X394500D02*
X393700Y-122267D01*
X393100Y-122933D01*
X392700Y-123733D01*
X392400Y-124800D01*
X392300Y-126000D01*
X392400Y-127200D01*
X392700Y-128267D01*
X393100Y-129067D01*
X393700Y-129733D01*
X394500Y-130000D01*
X395300Y-129733D01*
X395900Y-129067D01*
X396300Y-128267D01*
X396600Y-127200D01*
X396700Y-126000D01*
X396600Y-124800D01*
X396300Y-123733D01*
X395900Y-122933D01*
X395300Y-122267D01*
X394500Y-122000D01*
G01X400800Y-129067D02*
X401500Y-129733D01*
X402300Y-130000D01*
X403100Y-129733D01*
X403800Y-128934D01*
X404300Y-127733D01*
X404500Y-126533D01*
Y-125067D01*
X404300Y-123867D01*
X403800Y-122800D01*
X403200Y-122267D01*
X402500Y-122000D01*
X401700Y-122267D01*
X401100Y-122800D01*
X400700Y-123600D01*
X400500Y-124667D01*
X400700Y-125600D01*
X401200Y-126533D01*
X401800Y-127067D01*
X402500Y-127200D01*
X403300Y-126934D01*
X403900Y-126267D01*
X404500Y-125067D01*
G01X328300Y-105000D02*
Y-97000D01*
X330300D01*
X331100Y-97400D01*
X331700Y-97933D01*
X332200Y-98733D01*
X332600Y-99667D01*
X332700Y-101000D01*
X332600Y-102333D01*
X332200Y-103267D01*
X331700Y-104067D01*
X331100Y-104600D01*
X330300Y-105000D01*
X328300D01*
G01X336000D02*
X338500Y-97000D01*
X341000Y-105000D01*
G01X340100Y-102200D02*
X336900D01*
G01X346500Y-97000D02*
Y-105000D01*
G01X344200Y-97000D02*
X348800D01*
G01X352600Y-101667D02*
X353300Y-100733D01*
X353900Y-100200D01*
X354700Y-99933D01*
X355400Y-100200D01*
X355900Y-100733D01*
X356300Y-101533D01*
X356400Y-102467D01*
X356300Y-103267D01*
X355900Y-104067D01*
X355300Y-104733D01*
X354600Y-105000D01*
X353800Y-104733D01*
X353100Y-103934D01*
X352700Y-102733D01*
X352600Y-101400D01*
X352800Y-99667D01*
X353100Y-98733D01*
X353600Y-97800D01*
X354300Y-97133D01*
X355000Y-97000D01*
X355700Y-97267D01*
X356200Y-97933D01*
G01X359900Y-105000D02*
Y-97000D01*
X362500Y-103667D01*
X365100Y-97000D01*
Y-105000D01*
G01X370500Y-97000D02*
Y-105000D01*
G01X368200Y-97000D02*
X372800D01*
G01X379300Y-100733D02*
X379700Y-100333D01*
X380000Y-99667D01*
X380200Y-98733D01*
X380000Y-97933D01*
X379600Y-97400D01*
X378900Y-97000D01*
X376200D01*
Y-105000D01*
X379500D01*
X380200Y-104467D01*
X380600Y-103667D01*
X380800Y-102733D01*
X380600Y-101800D01*
X380000Y-101000D01*
X379300Y-100733D01*
X376200D01*
G01X386500Y-105000D02*
X387200Y-104867D01*
X388000Y-104467D01*
X388500Y-103800D01*
X388700Y-102867D01*
X388500Y-101934D01*
X387900Y-101133D01*
X387000Y-100733D01*
X386000D01*
X385400Y-100467D01*
X384900Y-99800D01*
X384700Y-98867D01*
X385000Y-97933D01*
X385700Y-97267D01*
X386500Y-97000D01*
X387300Y-97267D01*
X388000Y-97933D01*
X388300Y-98867D01*
X388100Y-99800D01*
X387600Y-100467D01*
X387000Y-100733D01*
X386000D01*
X385100Y-101133D01*
X384500Y-101934D01*
X384300Y-102867D01*
X384500Y-103800D01*
X385000Y-104467D01*
X385800Y-104867D01*
X386500Y-105000D01*
G01X394500D02*
X395200Y-104867D01*
X396000Y-104467D01*
X396500Y-103800D01*
X396700Y-102867D01*
X396500Y-101934D01*
X395900Y-101133D01*
X395000Y-100733D01*
X394000D01*
X393400Y-100467D01*
X392900Y-99800D01*
X392700Y-98867D01*
X393000Y-97933D01*
X393700Y-97267D01*
X394500Y-97000D01*
X395300Y-97267D01*
X396000Y-97933D01*
X396300Y-98867D01*
X396100Y-99800D01*
X395600Y-100467D01*
X395000Y-100733D01*
X394000D01*
X393100Y-101133D01*
X392500Y-101934D01*
X392300Y-102867D01*
X392500Y-103800D01*
X393000Y-104467D01*
X393800Y-104867D01*
X394500Y-105000D01*
G01X400000D02*
X402500Y-97000D01*
X405000Y-105000D01*
G01X404100Y-102200D02*
X400900D01*
G01X410500Y-97000D02*
X409700Y-97267D01*
X409100Y-97933D01*
X408700Y-98733D01*
X408400Y-99800D01*
X408300Y-101000D01*
X408400Y-102200D01*
X408700Y-103267D01*
X409100Y-104067D01*
X409700Y-104733D01*
X410500Y-105000D01*
X411300Y-104733D01*
X411900Y-104067D01*
X412300Y-103267D01*
X412600Y-102200D01*
X412700Y-101000D01*
X412600Y-99800D01*
X412300Y-98733D01*
X411900Y-97933D01*
X411300Y-97267D01*
X410500Y-97000D01*
G01X350500Y-72000D02*
Y-80000D01*
G01X348200Y-72000D02*
X352800D01*
G01X356600Y-76667D02*
X357300Y-75733D01*
X357900Y-75200D01*
X358700Y-74933D01*
X359400Y-75200D01*
X359900Y-75733D01*
X360300Y-76533D01*
X360400Y-77467D01*
X360300Y-78267D01*
X359900Y-79067D01*
X359300Y-79733D01*
X358600Y-80000D01*
X357800Y-79733D01*
X357100Y-78934D01*
X356700Y-77733D01*
X356600Y-76400D01*
X356800Y-74667D01*
X357100Y-73733D01*
X357600Y-72800D01*
X358300Y-72133D01*
X359000Y-72000D01*
X359700Y-72267D01*
X360200Y-72933D01*
G01X363900Y-80000D02*
Y-72000D01*
X366500Y-78667D01*
X369100Y-72000D01*
Y-80000D01*
G01X375100Y-76000D02*
X377100D01*
Y-78400D01*
X376500Y-79200D01*
X375800Y-79733D01*
X374800Y-80000D01*
X373800Y-79733D01*
X373100Y-79200D01*
X372500Y-78400D01*
X372100Y-77467D01*
X371900Y-76400D01*
Y-75467D01*
X372100Y-74667D01*
X372500Y-73733D01*
X373100Y-72933D01*
X373700Y-72400D01*
X374500Y-72000D01*
X375200D01*
X376000Y-72267D01*
X376600Y-72800D01*
G01X379500Y-82667D02*
X385500D01*
G01X388500Y-80000D02*
Y-72000D01*
X390900D01*
X391700Y-72400D01*
X392300Y-73333D01*
X392500Y-74400D01*
X392300Y-75467D01*
X391800Y-76267D01*
X390900Y-76667D01*
X388500D01*
G01X396300Y-80000D02*
Y-72000D01*
X398300D01*
X399100Y-72400D01*
X399700Y-72933D01*
X400200Y-73733D01*
X400600Y-74667D01*
X400700Y-76000D01*
X400600Y-77333D01*
X400200Y-78267D01*
X399700Y-79067D01*
X399100Y-79600D01*
X398300Y-80000D01*
X396300D01*
G01X407300Y-75733D02*
X407700Y-75333D01*
X408000Y-74667D01*
X408200Y-73733D01*
X408000Y-72933D01*
X407600Y-72400D01*
X406900Y-72000D01*
X404200D01*
Y-80000D01*
X407500D01*
X408200Y-79467D01*
X408600Y-78667D01*
X408800Y-77733D01*
X408600Y-76800D01*
X408000Y-76000D01*
X407300Y-75733D01*
X404200D01*
G01X411500Y-82667D02*
X417500D01*
G01X420000Y-80000D02*
X422500Y-72000D01*
X425000Y-80000D01*
G01X424100Y-77200D02*
X420900D01*
G01X427500Y-82667D02*
X433500D01*
G01X439300Y-75733D02*
X439700Y-75333D01*
X440000Y-74667D01*
X440200Y-73733D01*
X440000Y-72933D01*
X439600Y-72400D01*
X438900Y-72000D01*
X436200D01*
Y-80000D01*
X439500D01*
X440200Y-79467D01*
X440600Y-78667D01*
X440800Y-77733D01*
X440600Y-76800D01*
X440000Y-76000D01*
X439300Y-75733D01*
X436200D01*
G01X444300Y-80000D02*
Y-72000D01*
X446300D01*
X447100Y-72400D01*
X447700Y-72933D01*
X448200Y-73733D01*
X448600Y-74667D01*
X448700Y-76000D01*
X448600Y-77333D01*
X448200Y-78267D01*
X447700Y-79067D01*
X447100Y-79600D01*
X446300Y-80000D01*
X444300D01*
G01X443000Y-130000D02*
X445500Y-122000D01*
X448000Y-130000D01*
G01X447100Y-127200D02*
X443900D01*
G01X473000Y-130000D02*
Y-122000D01*
X471800Y-123600D01*
G01Y-130000D02*
X474200D01*
G01X479100Y-126667D02*
X479800Y-125733D01*
X480400Y-125200D01*
X481200Y-124933D01*
X481900Y-125200D01*
X482400Y-125733D01*
X482800Y-126533D01*
X482900Y-127467D01*
X482800Y-128267D01*
X482400Y-129067D01*
X481800Y-129733D01*
X481100Y-130000D01*
X480300Y-129733D01*
X479600Y-128934D01*
X479200Y-127733D01*
X479100Y-126400D01*
X479300Y-124667D01*
X479600Y-123733D01*
X480100Y-122800D01*
X480800Y-122133D01*
X481500Y-122000D01*
X482200Y-122267D01*
X482700Y-122933D01*
M02*
